FILE_TYPE = MACRO_DRAWING;
SET COLOR_WIRE YELLOW;
SET COLOR_PROP ORANGE;
SET COLOR_DOT WHITE;
SET COLOR_ARC YELLOW;
SET COLOR_BODY GREEN;
SET COLOR_NOTE PURPLE;
SET PROP_DISPLAY VALUE;
SET PAGE_NUMBER P141;
FORCEADD LSF0204DRUTR..1
(-4525 3300);
FORCEPROP 1 LAST LOCATION U116
J 0
(-4757 3708);
DISPLAY 0.489362 (-4757 3708);
PAINT SKYBLUE (-4757 3708);
FORCEPROP 0 LAST $SEC 1
J 0
(-4750 3850);
DISPLAY 0.680851 (-4750 3850);
PAINT MONO (-4750 3850);
DISPLAY INVISIBLE (-4750 3850);
FORCEPROP 0 LAST CDS_SEC 1
J 0
(-4750 3850);
DISPLAY 1.021277 (-4750 3850);
DISPLAY INVISIBLE (-4750 3850);
FORCEPROP 0 LASTPIN (-4900 3375) $PN 2
J 2
(-4910 3385);
DISPLAY 0.489362 (-4910 3385);
PAINT MONO (-4910 3385);
FORCEPROP 0 LASTPIN (-4900 3325) $PN 3
J 2
(-4910 3335);
DISPLAY 0.489362 (-4910 3335);
PAINT MONO (-4910 3335);
FORCEPROP 0 LASTPIN (-4900 3275) $PN 4
J 2
(-4910 3285);
DISPLAY 0.489362 (-4910 3285);
PAINT MONO (-4910 3285);
FORCEPROP 0 LASTPIN (-4900 3225) $PN 5
J 2
(-4910 3235);
DISPLAY 0.489362 (-4910 3235);
PAINT MONO (-4910 3235);
FORCEPROP 0 LASTPIN (-4150 3375) $PN 10
J 0
(-4140 3385);
DISPLAY 0.489362 (-4140 3385);
PAINT MONO (-4140 3385);
FORCEPROP 0 LASTPIN (-4150 3325) $PN 9
J 0
(-4140 3335);
DISPLAY 0.489362 (-4140 3335);
PAINT MONO (-4140 3335);
FORCEPROP 0 LASTPIN (-4150 3275) $PN 8
J 0
(-4140 3285);
DISPLAY 0.489362 (-4140 3285);
PAINT MONO (-4140 3285);
FORCEPROP 0 LASTPIN (-4150 3225) $PN 7
J 0
(-4140 3235);
DISPLAY 0.489362 (-4140 3235);
PAINT MONO (-4140 3235);
FORCEPROP 0 LASTPIN (-4900 3125) $PN 12
J 2
(-4910 3135);
DISPLAY 0.489362 (-4910 3135);
PAINT MONO (-4910 3135);
FORCEPROP 0 LASTPIN (-4150 3125) $PN 6
J 0
(-4140 3135);
DISPLAY 0.489362 (-4140 3135);
PAINT MONO (-4140 3135);
FORCEPROP 0 LASTPIN (-4900 3475) $PN 1
J 2
(-4910 3485);
DISPLAY 0.489362 (-4910 3485);
PAINT MONO (-4910 3485);
FORCEPROP 0 LASTPIN (-4150 3475) $PN 11
J 0
(-4140 3485);
DISPLAY 0.489362 (-4140 3485);
PAINT MONO (-4140 3485);
FORCEPROP 1 LAST MATERIAL IC
J 0
(-4757 3532);
DISPLAY 0.489362 (-4757 3532);
PAINT SKYBLUE (-4757 3532);
FORCEPROP 1 LAST PART_NUMBER AL000204002
J 0
(-4757 3616);
DISPLAY 0.489362 (-4757 3616);
PAINT SKYBLUE (-4757 3616);
FORCEPROP 2 LAST PART_TYPE SMLF
J 0
(-4750 3800);
DISPLAY 1.021277 (-4750 3800);
FORCEPROP 2 LAST VALUE LSF0204DRUTR
J 0
(-4750 3750);
DISPLAY 0.489362 (-4750 3750);
PAINT SKYBLUE (-4750 3750);
FORCEPROP 1 LAST PATH I117
J 0
(-4300 3075);
DISPLAY 0.723404 (-4300 3075);
PAINT GREEN (-4300 3075);
DISPLAY INVISIBLE (-4300 3075);
FORCEPROP 2 LAST CDS_LIB pure_quanta
J 0
(-4525 3300);
DISPLAY INVISIBLE (-4525 3300);
FORCEPROP 1 LAST CDS_LMAN_SYM_OUTLINE -225,225,225,-225
J 0
(-4525 3300);
DISPLAY 0.468085 (-4525 3300);
PAINT GREEN (-4525 3300);
DISPLAY INVISIBLE (-4525 3300);
FORCEPROP 1 LAST NEEDS_NO_SIZE TRUE
J 0
(-4300 3132);
DISPLAY 0.723404 (-4300 3132);
PAINT GREEN (-4300 3132);
DISPLAY INVISIBLE (-4300 3132);
FORCEADD UNIVERSAL_GND..1
R 2
(-3950 2925);
FORCEPROP 3 LASTPIN (-3950 2975) SIG_NAME GND\g
J 0
(-3940 2985);
DISPLAY 0.659574 (-3940 2985);
PAINT MONO (-3940 2985);
DISPLAY INVISIBLE (-3940 2985);
FORCEPROP 1 LAST HDL_POWER GND
J 1
(-3975 2850);
DISPLAY 0.702128 (-3975 2850);
PAINT GREEN (-3975 2850);
DISPLAY INVISIBLE (-3975 2850);
FORCEPROP 1 LAST PATH I118
J 2
(-4025 2925);
DISPLAY 0.872340 (-4025 2925);
PAINT AQUA (-4025 2925);
DISPLAY INVISIBLE (-4025 2925);
FORCEPROP 2 LAST CDS_LIB pure_quanta_power
J 0
(-3950 2925);
DISPLAY INVISIBLE (-3950 2925);
FORCEADD UNIVERSAL_POWER..1
(-1350 4175);
FORCEPROP 3 LASTPIN (-1350 4125) SIG_NAME P3V3_STBY\g
J 0
(-1340 4135);
DISPLAY 0.659574 (-1340 4135);
PAINT MONO (-1340 4135);
DISPLAY INVISIBLE (-1340 4135);
FORCEPROP 1 LAST HDL_POWER P3V3_STBY
J 1
(-1350 4225);
DISPLAY 0.489362 (-1350 4225);
PAINT GREEN (-1350 4225);
FORCEPROP 1 LAST PATH I120
J 0
(-1300 4200);
DISPLAY 0.872340 (-1300 4200);
PAINT AQUA (-1300 4200);
DISPLAY INVISIBLE (-1300 4200);
FORCEPROP 2 LAST CDS_LIB pure_quanta_power
J 0
(-1350 4175);
DISPLAY INVISIBLE (-1350 4175);
FORCEADD OFFPAGE..2
(-1975 3375);
FORCEPROP 2 LAST $XR2 118 
J 0
(-1546 3375);
DISPLAY 0.638298 (-1546 3375);
PAINT MONO (-1546 3375);
FORCEPROP 2 LAST $XR1 117 
J 0
(-1666 3375);
DISPLAY 0.638298 (-1666 3375);
PAINT MONO (-1666 3375);
FORCEPROP 2 LAST $XR0 141 
J 0
(-1786 3375);
DISPLAY 0.638298 (-1786 3375);
PAINT MONO (-1786 3375);
FORCEPROP 2 LAST PATH I123
J 0
(-1650 3425);
DISPLAY 1.021277 (-1650 3425);
DISPLAY INVISIBLE (-1650 3425);
FORCEPROP 1 LAST COMMENT_BODY TRUE
J 0
(-2020 3280);
DISPLAY 0.872340 (-2020 3280);
PAINT PEACH (-2020 3280);
DISPLAY INVISIBLE (-2020 3280);
FORCEPROP 1 LAST OFFPAGE TRUE
J 0
(-1650 3250);
DISPLAY 0.872340 (-1650 3250);
PAINT GREEN (-1650 3250);
DISPLAY INVISIBLE (-1650 3250);
FORCEPROP 2 LAST CDS_LIB standard
J 0
(-1975 3375);
DISPLAY INVISIBLE (-1975 3375);
FORCEADD OFFPAGE..2
R 2
(-2275 3700);
FORCEPROP 2 LAST $XR2 118 
J 0
(-2770 3700);
DISPLAY 0.638298 (-2770 3700);
PAINT MONO (-2770 3700);
FORCEPROP 2 LAST $XR1 117 
J 0
(-2650 3700);
DISPLAY 0.638298 (-2650 3700);
PAINT MONO (-2650 3700);
FORCEPROP 2 LAST $XR0 141 
J 0
(-2530 3700);
DISPLAY 0.638298 (-2530 3700);
PAINT MONO (-2530 3700);
FORCEPROP 2 LAST PATH I126
J 0
(-2525 3750);
DISPLAY 1.021277 (-2525 3750);
DISPLAY INVISIBLE (-2525 3750);
FORCEPROP 1 LAST COMMENT_BODY TRUE
J 2
(-2230 3605);
DISPLAY 0.872340 (-2230 3605);
PAINT PEACH (-2230 3605);
DISPLAY INVISIBLE (-2230 3605);
FORCEPROP 1 LAST OFFPAGE TRUE
J 2
(-2600 3575);
DISPLAY 0.872340 (-2600 3575);
PAINT GREEN (-2600 3575);
DISPLAY INVISIBLE (-2600 3575);
FORCEPROP 2 LAST CDS_LIB standard
J 2
(-2275 3700);
DISPLAY INVISIBLE (-2275 3700);
FORCEADD UNIVERSAL_POWER..1
(-3975 3975);
FORCEPROP 3 LASTPIN (-3975 3925) SIG_NAME P3V3_STBY\g
J 0
(-3965 3935);
DISPLAY 0.659574 (-3965 3935);
PAINT MONO (-3965 3935);
DISPLAY INVISIBLE (-3965 3935);
FORCEPROP 1 LAST HDL_POWER P3V3_STBY
J 1
(-3975 4025);
DISPLAY 0.489362 (-3975 4025);
PAINT GREEN (-3975 4025);
FORCEPROP 1 LAST PATH I128
J 0
(-3925 4000);
DISPLAY 0.872340 (-3925 4000);
PAINT AQUA (-3925 4000);
DISPLAY INVISIBLE (-3925 4000);
FORCEPROP 2 LAST CDS_LIB pure_quanta_power
J 0
(-3975 3975);
DISPLAY INVISIBLE (-3975 3975);
FORCEADD Q_RES..1
(-3075 3375);
FORCEPROP 1 LAST LOCATION R1425
J 0
(-3300 3375);
DISPLAY 0.489362 (-3300 3375);
PAINT SKYBLUE (-3300 3375);
FORCEPROP 0 LAST $SEC 1
J 0
(-2975 3400);
DISPLAY 0.680851 (-2975 3400);
PAINT MONO (-2975 3400);
DISPLAY INVISIBLE (-2975 3400);
FORCEPROP 0 LAST CDS_SEC 1
J 0
(-2975 3400);
DISPLAY 1.021277 (-2975 3400);
DISPLAY INVISIBLE (-2975 3400);
FORCEPROP 1 LASTPIN (-3175 3375) $PN 1
J 0
(-3163 3387);
DISPLAY 0.489362 (-3163 3387);
PAINT MONO (-3163 3387);
FORCEPROP 1 LASTPIN (-2975 3375) $PN 2
J 0
(-3013 3387);
DISPLAY 0.489362 (-3013 3387);
PAINT MONO (-3013 3387);
FORCEPROP 1 LAST VALUE 0
J 2
(-2875 3375);
DISPLAY 0.489362 (-2875 3375);
PAINT SKYBLUE (-2875 3375);
FORCEPROP 1 LAST PACK_TYPE 0402LF
J 0
(-3025 3300);
DISPLAY 0.489362 (-3025 3300);
PAINT SKYBLUE (-3025 3300);
DISPLAY INVISIBLE (-3025 3300);
FORCEPROP 1 LAST PART_NUMBER CS00002JB38
J 0
(-3050 3425);
DISPLAY 0.489362 (-3050 3425);
PAINT SKYBLUE (-3050 3425);
DISPLAY INVISIBLE (-3050 3425);
FORCEPROP 1 LAST TOLERANCE 5%
J 0
(-3100 3300);
DISPLAY 0.489362 (-3100 3300);
PAINT SKYBLUE (-3100 3300);
DISPLAY INVISIBLE (-3100 3300);
FORCEPROP 1 LAST MATERIAL CHIP
J 0
(-2650 3300);
DISPLAY 0.489362 (-2650 3300);
PAINT SKYBLUE (-2650 3300);
DISPLAY INVISIBLE (-2650 3300);
FORCEPROP 1 LAST WATTAGE 1/16W
J 2
(-2675 3300);
DISPLAY 0.489362 (-2675 3300);
PAINT SKYBLUE (-2675 3300);
DISPLAY INVISIBLE (-2675 3300);
FORCEPROP 1 LAST PATH I131
J 0
(-3125 3525);
DISPLAY 0.978723 (-3125 3525);
PAINT WHITE (-3125 3525);
DISPLAY INVISIBLE (-3125 3525);
FORCEPROP 2 LAST CDS_LIB pure_quanta
J 0
(-3075 3375);
DISPLAY INVISIBLE (-3075 3375);
FORCEADD Q_CAP..1
(-3850 3725);
FORCEPROP 1 LAST LOCATION C1354
J 0
(-3800 3825);
DISPLAY 0.489362 (-3800 3825);
PAINT SKYBLUE (-3800 3825);
FORCEPROP 0 LAST $SEC 1
J 0
(-3800 3850);
DISPLAY 0.680851 (-3800 3850);
PAINT MONO (-3800 3850);
DISPLAY INVISIBLE (-3800 3850);
FORCEPROP 0 LAST CDS_SEC 1
J 0
(-3800 3850);
DISPLAY 1.021277 (-3800 3850);
DISPLAY INVISIBLE (-3800 3850);
FORCEPROP 1 LASTPIN (-3850 3825) $PN 1
J 0
(-3840 3805);
DISPLAY 0.489362 (-3840 3805);
PAINT MONO (-3840 3805);
FORCEPROP 1 LASTPIN (-3850 3625) $PN 2
J 0
(-3840 3605);
DISPLAY 0.489362 (-3840 3605);
PAINT MONO (-3840 3605);
FORCEPROP 1 LAST PACK_TYPE 0402
J 0
(-3800 3650);
DISPLAY 0.489362 (-3800 3650);
PAINT SKYBLUE (-3800 3650);
FORCEPROP 1 LAST VOLTAGE 25V
J 0
(-3800 3750);
DISPLAY 0.489362 (-3800 3750);
PAINT SKYBLUE (-3800 3750);
FORCEPROP 1 LAST PART_NUMBER CH4104K1B00
J 0
(-3800 3675);
DISPLAY 0.489362 (-3800 3675);
PAINT SKYBLUE (-3800 3675);
FORCEPROP 1 LAST VALUE 0.1UF
J 0
(-3800 3775);
DISPLAY 0.489362 (-3800 3775);
PAINT SKYBLUE (-3800 3775);
FORCEPROP 1 LAST TOLERANCE 10%
J 0
(-3800 3725);
DISPLAY 0.489362 (-3800 3725);
PAINT SKYBLUE (-3800 3725);
FORCEPROP 1 LAST MATERIAL X7R
J 0
(-3800 3700);
DISPLAY 0.489362 (-3800 3700);
PAINT SKYBLUE (-3800 3700);
FORCEPROP 1 LAST PATH I133
J 0
(-3800 3875);
DISPLAY 0.978723 (-3800 3875);
PAINT WHITE (-3800 3875);
DISPLAY INVISIBLE (-3800 3875);
FORCEPROP 2 LAST CDS_LIB pure_quanta
J 2
(-3850 3725);
DISPLAY INVISIBLE (-3850 3725);
FORCEADD UNIVERSAL_GND..1
R 2
(-3850 3525);
FORCEPROP 3 LASTPIN (-3850 3575) SIG_NAME GND\g
J 0
(-3840 3585);
DISPLAY 0.659574 (-3840 3585);
PAINT MONO (-3840 3585);
DISPLAY INVISIBLE (-3840 3585);
FORCEPROP 1 LAST HDL_POWER GND
J 1
(-3875 3450);
DISPLAY 0.872340 (-3875 3450);
PAINT GREEN (-3875 3450);
DISPLAY INVISIBLE (-3875 3450);
FORCEPROP 1 LAST PATH I134
J 2
(-3925 3525);
DISPLAY 0.872340 (-3925 3525);
PAINT AQUA (-3925 3525);
DISPLAY INVISIBLE (-3925 3525);
FORCEPROP 2 LAST CDS_LIB pure_quanta_power
J 2
(-3850 3525);
DISPLAY INVISIBLE (-3850 3525);
FORCEADD UNIVERSAL_POWER..1
(-5050 3950);
FORCEPROP 3 LASTPIN (-5050 3900) SIG_NAME PVDD18_S5_P0\g
J 0
(-5040 3910);
DISPLAY 0.659574 (-5040 3910);
PAINT MONO (-5040 3910);
DISPLAY INVISIBLE (-5040 3910);
FORCEPROP 1 LAST HDL_POWER PVDD18_S5_P0
J 1
(-5050 4000);
DISPLAY 0.489362 (-5050 4000);
PAINT GREEN (-5050 4000);
FORCEPROP 1 LAST PATH I135
J 0
(-5000 3975);
DISPLAY 0.872340 (-5000 3975);
PAINT AQUA (-5000 3975);
DISPLAY INVISIBLE (-5000 3975);
FORCEPROP 2 LAST CDS_LIB pure_quanta_power
J 0
(-5050 3950);
DISPLAY INVISIBLE (-5050 3950);
FORCEADD UNIVERSAL_GND..1
(-5175 3525);
FORCEPROP 3 LASTPIN (-5175 3575) SIG_NAME GND\g
J 0
(-5165 3585);
DISPLAY 0.659574 (-5165 3585);
PAINT MONO (-5165 3585);
DISPLAY INVISIBLE (-5165 3585);
FORCEPROP 1 LAST HDL_POWER GND
J 1
(-5150 3450);
DISPLAY 0.872340 (-5150 3450);
PAINT GREEN (-5150 3450);
DISPLAY INVISIBLE (-5150 3450);
FORCEPROP 1 LAST PATH I136
J 0
(-5100 3525);
DISPLAY 0.872340 (-5100 3525);
PAINT AQUA (-5100 3525);
DISPLAY INVISIBLE (-5100 3525);
FORCEPROP 2 LAST CDS_LIB pure_quanta_power
J 0
(-5175 3525);
PAINT MONO (-5175 3525);
DISPLAY INVISIBLE (-5175 3525);
FORCEADD Q_CAP..1
R 2
(-5175 3725);
FORCEPROP 1 LAST LOCATION C1352
J 2
(-5225 3800);
DISPLAY 0.489362 (-5225 3800);
PAINT SKYBLUE (-5225 3800);
FORCEPROP 2 LAST $SEC 1
J 0
(-5225 3925);
DISPLAY 0.680851 (-5225 3925);
PAINT MONO (-5225 3925);
DISPLAY INVISIBLE (-5225 3925);
FORCEPROP 2 LAST CDS_SEC 1
J 0
(-5225 3925);
DISPLAY 1.021277 (-5225 3925);
DISPLAY INVISIBLE (-5225 3925);
FORCEPROP 1 LASTPIN (-5175 3825) $PN 1
J 2
(-5185 3805);
DISPLAY 0.489362 (-5185 3805);
FORCEPROP 1 LASTPIN (-5175 3625) $PN 2
J 2
(-5185 3605);
DISPLAY 0.489362 (-5185 3605);
FORCEPROP 1 LAST PACK_TYPE 0402
J 2
(-5225 3650);
DISPLAY 0.489362 (-5225 3650);
PAINT SKYBLUE (-5225 3650);
FORCEPROP 1 LAST VOLTAGE 25V
J 2
(-5225 3750);
DISPLAY 0.489362 (-5225 3750);
PAINT SKYBLUE (-5225 3750);
FORCEPROP 1 LAST PART_NUMBER CH4104K1B00
J 2
(-5225 3675);
DISPLAY 0.489362 (-5225 3675);
PAINT SKYBLUE (-5225 3675);
FORCEPROP 1 LAST VALUE 0.1UF
J 2
(-5225 3775);
DISPLAY 0.489362 (-5225 3775);
PAINT SKYBLUE (-5225 3775);
FORCEPROP 1 LAST TOLERANCE 10%
J 2
(-5225 3725);
DISPLAY 0.489362 (-5225 3725);
PAINT SKYBLUE (-5225 3725);
FORCEPROP 1 LAST MATERIAL X7R
J 2
(-5225 3700);
DISPLAY 0.489362 (-5225 3700);
PAINT SKYBLUE (-5225 3700);
FORCEPROP 1 LAST PATH I137
J 2
(-5225 3875);
DISPLAY 0.978723 (-5225 3875);
PAINT WHITE (-5225 3875);
DISPLAY INVISIBLE (-5225 3875);
FORCEPROP 2 LAST CDS_LIB pure_quanta
J 0
(-5175 3725);
PAINT MONO (-5175 3725);
DISPLAY INVISIBLE (-5175 3725);
FORCEADD OFFPAGE..2
(-5800 3775);
FORCEPROP 2 LAST $XR1 27 
J 0
(-5491 3775);
DISPLAY 0.638298 (-5491 3775);
PAINT MONO (-5491 3775);
FORCEPROP 2 LAST $XR0 141 
J 0
(-5611 3775);
DISPLAY 0.638298 (-5611 3775);
PAINT MONO (-5611 3775);
FORCEPROP 2 LAST PATH I138
J 0
(-5425 3825);
DISPLAY 1.021277 (-5425 3825);
DISPLAY INVISIBLE (-5425 3825);
FORCEPROP 1 LAST COMMENT_BODY TRUE
J 0
(-5845 3680);
DISPLAY 0.872340 (-5845 3680);
PAINT PEACH (-5845 3680);
DISPLAY INVISIBLE (-5845 3680);
FORCEPROP 1 LAST OFFPAGE TRUE
J 0
(-5475 3650);
DISPLAY 0.872340 (-5475 3650);
PAINT GREEN (-5475 3650);
DISPLAY INVISIBLE (-5475 3650);
FORCEPROP 2 LAST CDS_LIB standard
J 0
(-5800 3775);
DISPLAY INVISIBLE (-5800 3775);
FORCEADD OFFPAGE..2
R 2
(-6675 3325);
FORCEPROP 2 LAST $XR1 27 
J 0
(-7020 3325);
DISPLAY 0.638298 (-7020 3325);
PAINT MONO (-7020 3325);
FORCEPROP 2 LAST $XR0 141 
J 0
(-6930 3325);
DISPLAY 0.638298 (-6930 3325);
PAINT MONO (-6930 3325);
FORCEPROP 2 LAST PATH I141
J 0
(-6625 3400);
DISPLAY 1.021277 (-6625 3400);
DISPLAY INVISIBLE (-6625 3400);
FORCEPROP 1 LAST COMMENT_BODY TRUE
J 2
(-6630 3230);
DISPLAY 0.872340 (-6630 3230);
PAINT PEACH (-6630 3230);
DISPLAY INVISIBLE (-6630 3230);
FORCEPROP 1 LAST OFFPAGE TRUE
J 2
(-7000 3200);
DISPLAY 0.872340 (-7000 3200);
PAINT GREEN (-7000 3200);
DISPLAY INVISIBLE (-7000 3200);
FORCEPROP 2 LAST CDS_LIB standard
J 2
(-6675 3325);
DISPLAY INVISIBLE (-6675 3325);
FORCEADD OFFPAGE..1
(-5875 3125);
FORCEPROP 2 LAST $XR0 141 
J 0
(-6127 3125);
DISPLAY 0.638298 (-6127 3125);
PAINT MONO (-6127 3125);
FORCEPROP 2 LAST PATH I144
J 0
(-5825 3200);
DISPLAY 1.021277 (-5825 3200);
DISPLAY INVISIBLE (-5825 3200);
FORCEPROP 1 LAST COMMENT_BODY TRUE
J 0
(-5745 3025);
DISPLAY 1.106383 (-5745 3025);
PAINT PEACH (-5745 3025);
DISPLAY INVISIBLE (-5745 3025);
FORCEPROP 1 LAST OFFPAGE TRUE
J 0
(-5545 2995);
PAINT GREEN (-5545 2995);
DISPLAY INVISIBLE (-5545 2995);
FORCEPROP 2 LAST CDS_LIB standard
J 0
(-5875 3125);
DISPLAY INVISIBLE (-5875 3125);
FORCEADD UNIVERSAL_POWER..1
(-6925 4250);
FORCEPROP 3 LASTPIN (-6925 4200) SIG_NAME PVDD18_S5_P0\g
J 0
(-6915 4210);
DISPLAY 0.659574 (-6915 4210);
PAINT MONO (-6915 4210);
DISPLAY INVISIBLE (-6915 4210);
FORCEPROP 1 LAST HDL_POWER PVDD18_S5_P0
J 1
(-6925 4300);
DISPLAY 0.489362 (-6925 4300);
PAINT GREEN (-6925 4300);
FORCEPROP 1 LAST PATH I145
J 0
(-6875 4275);
DISPLAY 0.872340 (-6875 4275);
PAINT AQUA (-6875 4275);
DISPLAY INVISIBLE (-6875 4275);
FORCEPROP 2 LAST CDS_LIB pure_quanta_power
J 0
(-6925 4250);
DISPLAY INVISIBLE (-6925 4250);
FORCEADD Q_RES..1
(-5800 3325);
FORCEPROP 1 LAST LOCATION R1423
J 0
(-6000 3325);
DISPLAY 0.489362 (-6000 3325);
PAINT SKYBLUE (-6000 3325);
FORCEPROP 0 LAST $SEC 1
J 0
(-5675 3375);
DISPLAY 0.680851 (-5675 3375);
PAINT MONO (-5675 3375);
DISPLAY INVISIBLE (-5675 3375);
FORCEPROP 0 LAST CDS_SEC 1
J 0
(-5675 3375);
DISPLAY 1.021277 (-5675 3375);
DISPLAY INVISIBLE (-5675 3375);
FORCEPROP 1 LASTPIN (-5900 3325) $PN 1
J 0
(-5888 3337);
DISPLAY 0.489362 (-5888 3337);
PAINT MONO (-5888 3337);
FORCEPROP 1 LASTPIN (-5700 3325) $PN 2
J 0
(-5738 3337);
DISPLAY 0.489362 (-5738 3337);
PAINT MONO (-5738 3337);
FORCEPROP 1 LAST VALUE 0
J 2
(-5650 3325);
DISPLAY 0.489362 (-5650 3325);
PAINT SKYBLUE (-5650 3325);
FORCEPROP 1 LAST PACK_TYPE 0402LF
J 0
(-5750 3250);
DISPLAY 0.489362 (-5750 3250);
PAINT SKYBLUE (-5750 3250);
DISPLAY INVISIBLE (-5750 3250);
FORCEPROP 1 LAST PART_NUMBER CS00002JB38
J 0
(-5775 3375);
DISPLAY 0.489362 (-5775 3375);
PAINT SKYBLUE (-5775 3375);
DISPLAY INVISIBLE (-5775 3375);
FORCEPROP 1 LAST TOLERANCE 5%
J 0
(-5825 3250);
DISPLAY 0.489362 (-5825 3250);
PAINT SKYBLUE (-5825 3250);
DISPLAY INVISIBLE (-5825 3250);
FORCEPROP 1 LAST MATERIAL CHIP
J 0
(-5375 3250);
DISPLAY 0.489362 (-5375 3250);
PAINT SKYBLUE (-5375 3250);
DISPLAY INVISIBLE (-5375 3250);
FORCEPROP 1 LAST WATTAGE 1/16W
J 2
(-5400 3250);
DISPLAY 0.489362 (-5400 3250);
PAINT SKYBLUE (-5400 3250);
DISPLAY INVISIBLE (-5400 3250);
FORCEPROP 1 LAST PATH I147
J 0
(-5850 3475);
DISPLAY 0.978723 (-5850 3475);
PAINT WHITE (-5850 3475);
DISPLAY INVISIBLE (-5850 3475);
FORCEPROP 2 LAST CDS_LIB pure_quanta
J 0
(-5800 3325);
DISPLAY INVISIBLE (-5800 3325);
FORCEADD UNIVERSAL_POWER..1
(-6875 2750);
FORCEPROP 3 LASTPIN (-6875 2700) SIG_NAME PVDD18_S5_P0\g
J 0
(-6865 2710);
DISPLAY 0.659574 (-6865 2710);
PAINT MONO (-6865 2710);
DISPLAY INVISIBLE (-6865 2710);
FORCEPROP 1 LAST HDL_POWER PVDD18_S5_P0
J 1
(-6875 2800);
DISPLAY 0.489362 (-6875 2800);
PAINT GREEN (-6875 2800);
FORCEPROP 1 LAST PATH I148
J 0
(-6825 2775);
DISPLAY 0.872340 (-6825 2775);
PAINT AQUA (-6825 2775);
DISPLAY INVISIBLE (-6825 2775);
FORCEPROP 2 LAST CDS_LIB pure_quanta_power
J 0
(-6875 2750);
DISPLAY INVISIBLE (-6875 2750);
FORCEADD OFFPAGE..1
(-6675 3375);
FORCEPROP 2 LAST $XR2 141 
J 0
(-7136 3375);
DISPLAY 0.638298 (-7136 3375);
PAINT MONO (-7136 3375);
FORCEPROP 2 LAST $XR1 75 
J 0
(-7016 3375);
DISPLAY 0.638298 (-7016 3375);
PAINT MONO (-7016 3375);
FORCEPROP 2 LAST $XR0 27 
J 0
(-6926 3375);
DISPLAY 0.638298 (-6926 3375);
PAINT MONO (-6926 3375);
FORCEPROP 2 LAST PATH I150
J 0
(-6925 3425);
DISPLAY 1.021277 (-6925 3425);
DISPLAY INVISIBLE (-6925 3425);
FORCEPROP 1 LAST COMMENT_BODY TRUE
J 0
(-6545 3275);
DISPLAY 1.106383 (-6545 3275);
PAINT PEACH (-6545 3275);
DISPLAY INVISIBLE (-6545 3275);
FORCEPROP 1 LAST OFFPAGE TRUE
J 0
(-6345 3245);
PAINT GREEN (-6345 3245);
DISPLAY INVISIBLE (-6345 3245);
FORCEPROP 2 LAST CDS_LIB standard
J 0
(-6675 3375);
DISPLAY INVISIBLE (-6675 3375);
FORCEADD OFFPAGE..1
R 2
(-1975 3325);
FORCEPROP 2 LAST $XR2 141 
J 0
(-1549 3325);
DISPLAY 0.638298 (-1549 3325);
PAINT MONO (-1549 3325);
FORCEPROP 2 LAST $XR1 118 
J 0
(-1669 3325);
DISPLAY 0.638298 (-1669 3325);
PAINT MONO (-1669 3325);
FORCEPROP 2 LAST $XR0 117 
J 0
(-1789 3325);
DISPLAY 0.638298 (-1789 3325);
PAINT MONO (-1789 3325);
FORCEPROP 2 LAST PATH I154
J 0
(-1775 3375);
DISPLAY 1.021277 (-1775 3375);
DISPLAY INVISIBLE (-1775 3375);
FORCEPROP 1 LAST COMMENT_BODY TRUE
J 2
(-2105 3225);
DISPLAY 1.106383 (-2105 3225);
PAINT PEACH (-2105 3225);
DISPLAY INVISIBLE (-2105 3225);
FORCEPROP 1 LAST OFFPAGE TRUE
J 2
(-2305 3195);
PAINT GREEN (-2305 3195);
DISPLAY INVISIBLE (-2305 3195);
FORCEPROP 2 LAST CDS_LIB standard
J 2
(-1975 3325);
DISPLAY INVISIBLE (-1975 3325);
FORCEADD Q_RES..1
(-5800 3225);
FORCEPROP 1 LAST LOCATION R817
J 0
(-6000 3225);
DISPLAY 0.489362 (-6000 3225);
PAINT SKYBLUE (-6000 3225);
FORCEPROP 2 LAST $SEC 1
J 0
(-5850 3425);
DISPLAY 0.680851 (-5850 3425);
PAINT MONO (-5850 3425);
DISPLAY INVISIBLE (-5850 3425);
FORCEPROP 2 LAST CDS_SEC 1
J 0
(-5850 3425);
DISPLAY 0.680851 (-5850 3425);
DISPLAY INVISIBLE (-5850 3425);
FORCEPROP 1 LASTPIN (-5900 3225) $PN 1
J 0
(-5888 3237);
DISPLAY 0.489362 (-5888 3237);
PAINT MONO (-5888 3237);
FORCEPROP 1 LASTPIN (-5700 3225) $PN 2
J 0
(-5738 3237);
DISPLAY 0.489362 (-5738 3237);
PAINT MONO (-5738 3237);
FORCEPROP 1 LAST VALUE 0
J 2
(-5650 3225);
DISPLAY 0.489362 (-5650 3225);
PAINT SKYBLUE (-5650 3225);
FORCEPROP 1 LAST PACK_TYPE 0402LF
J 0
(-5750 3150);
DISPLAY 0.489362 (-5750 3150);
PAINT SKYBLUE (-5750 3150);
DISPLAY INVISIBLE (-5750 3150);
FORCEPROP 1 LAST PART_NUMBER CS00002JB38
J 0
(-5775 3275);
DISPLAY 0.489362 (-5775 3275);
PAINT SKYBLUE (-5775 3275);
DISPLAY INVISIBLE (-5775 3275);
FORCEPROP 1 LAST TOLERANCE 5%
J 0
(-5825 3150);
DISPLAY 0.489362 (-5825 3150);
PAINT SKYBLUE (-5825 3150);
DISPLAY INVISIBLE (-5825 3150);
FORCEPROP 1 LAST MATERIAL CHIP
J 0
(-5375 3150);
DISPLAY 0.489362 (-5375 3150);
PAINT SKYBLUE (-5375 3150);
DISPLAY INVISIBLE (-5375 3150);
FORCEPROP 1 LAST WATTAGE 1/16W
J 2
(-5400 3150);
DISPLAY 0.489362 (-5400 3150);
PAINT SKYBLUE (-5400 3150);
DISPLAY INVISIBLE (-5400 3150);
FORCEPROP 1 LAST PATH I176
J 0
(-5850 3375);
DISPLAY 0.978723 (-5850 3375);
PAINT WHITE (-5850 3375);
DISPLAY INVISIBLE (-5850 3375);
FORCEPROP 2 LAST CDS_LIB pure_quanta
J 0
(-5800 3225);
DISPLAY INVISIBLE (-5800 3225);
FORCEADD OFFPAGE..1
(-6675 3275);
FORCEPROP 2 LAST $XR1 141 
J 0
(-7046 3275);
DISPLAY 0.638298 (-7046 3275);
PAINT MONO (-7046 3275);
FORCEPROP 2 LAST $XR0 27 
J 0
(-6926 3275);
DISPLAY 0.638298 (-6926 3275);
PAINT MONO (-6926 3275);
FORCEPROP 2 LAST PATH I177
J 0
(-6625 3350);
DISPLAY 1.021277 (-6625 3350);
DISPLAY INVISIBLE (-6625 3350);
FORCEPROP 1 LAST COMMENT_BODY TRUE
J 0
(-6545 3175);
DISPLAY 1.106383 (-6545 3175);
PAINT PEACH (-6545 3175);
DISPLAY INVISIBLE (-6545 3175);
FORCEPROP 1 LAST OFFPAGE TRUE
J 0
(-6345 3145);
PAINT GREEN (-6345 3145);
DISPLAY INVISIBLE (-6345 3145);
FORCEPROP 2 LAST CDS_LIB standard
J 0
(-6675 3275);
DISPLAY INVISIBLE (-6675 3275);
FORCEADD OFFPAGE..2
R 2
(-6675 3225);
FORCEPROP 2 LAST $XR1 27 
J 0
(-7020 3225);
DISPLAY 0.638298 (-7020 3225);
PAINT MONO (-7020 3225);
FORCEPROP 2 LAST $XR0 141 
J 0
(-6930 3225);
DISPLAY 0.638298 (-6930 3225);
PAINT MONO (-6930 3225);
FORCEPROP 2 LAST PATH I178
J 0
(-6625 3300);
DISPLAY 1.021277 (-6625 3300);
DISPLAY INVISIBLE (-6625 3300);
FORCEPROP 1 LAST COMMENT_BODY TRUE
J 2
(-6630 3130);
DISPLAY 0.872340 (-6630 3130);
PAINT PEACH (-6630 3130);
DISPLAY INVISIBLE (-6630 3130);
FORCEPROP 1 LAST OFFPAGE TRUE
J 2
(-7000 3100);
DISPLAY 0.872340 (-7000 3100);
PAINT GREEN (-7000 3100);
DISPLAY INVISIBLE (-7000 3100);
FORCEPROP 2 LAST CDS_LIB standard
J 0
(-6675 3225);
DISPLAY INVISIBLE (-6675 3225);
FORCEADD UNIVERSAL_GND..1
R 2
(-1975 1175);
FORCEPROP 3 LASTPIN (-1975 1225) SIG_NAME GND\g
J 0
(-1965 1235);
DISPLAY 0.659574 (-1965 1235);
PAINT MONO (-1965 1235);
DISPLAY INVISIBLE (-1965 1235);
FORCEPROP 1 LAST HDL_POWER GND
J 1
(-2000 1100);
DISPLAY 0.872340 (-2000 1100);
PAINT GREEN (-2000 1100);
DISPLAY INVISIBLE (-2000 1100);
FORCEPROP 1 LAST PATH I180
J 2
(-2050 1175);
DISPLAY 0.872340 (-2050 1175);
PAINT AQUA (-2050 1175);
DISPLAY INVISIBLE (-2050 1175);
FORCEPROP 2 LAST CDS_LIB pure_quanta_power
J 0
(-1975 1175);
DISPLAY INVISIBLE (-1975 1175);
FORCEADD UNIVERSAL_POWER..1
(-2150 1325);
FORCEPROP 3 LASTPIN (-2150 1275) SIG_NAME P3V3_STBY\g
J 0
(-2140 1285);
DISPLAY 0.659574 (-2140 1285);
PAINT MONO (-2140 1285);
DISPLAY INVISIBLE (-2140 1285);
FORCEPROP 1 LAST HDL_POWER P3V3_STBY
J 1
(-2150 1375);
DISPLAY 0.489362 (-2150 1375);
PAINT GREEN (-2150 1375);
FORCEPROP 1 LAST PATH I181
J 0
(-2100 1350);
DISPLAY 0.872340 (-2100 1350);
PAINT AQUA (-2100 1350);
DISPLAY INVISIBLE (-2100 1350);
FORCEPROP 2 LAST BOM_COST VR_SYSTEM 
J 0
(-2150 1425);
DISPLAY 0.680851 (-2150 1425);
DISPLAY INVISIBLE (-2150 1425);
FORCEPROP 2 LAST CDS_LIB pure_quanta_power
J 0
(-2150 1325);
DISPLAY INVISIBLE (-2150 1325);
FORCEADD P1V0..1
(-2375 1325);
FORCEPROP 3 LASTPIN (-2375 1275) SIG_NAME P5V_STBY\g
J 0
(-2365 1285);
DISPLAY 0.659574 (-2365 1285);
PAINT MONO (-2365 1285);
DISPLAY INVISIBLE (-2365 1285);
FORCEPROP 1 LAST HDL_POWER P5V_STBY
J 1
(-2375 1375);
DISPLAY 0.489362 (-2375 1375);
PAINT GREEN (-2375 1375);
FORCEPROP 1 LAST PATH I182
J 0
(-2325 1350);
DISPLAY 0.872340 (-2325 1350);
PAINT AQUA (-2325 1350);
DISPLAY INVISIBLE (-2325 1350);
FORCEPROP 2 LAST CDS_LIB pure_quanta_power
J 0
(-2375 1325);
DISPLAY INVISIBLE (-2375 1325);
FORCEADD OFFPAGE..1
(-3925 1475);
FORCEPROP 2 LAST $XR0 141 
J 0
(-4177 1475);
DISPLAY 0.638298 (-4177 1475);
PAINT MONO (-4177 1475);
FORCEPROP 2 LAST PATH I184
J 0
(-3875 1550);
DISPLAY 1.021277 (-3875 1550);
DISPLAY INVISIBLE (-3875 1550);
FORCEPROP 1 LAST COMMENT_BODY TRUE
J 0
(-3800 1375);
DISPLAY 0.872340 (-3800 1375);
PAINT GREEN (-3800 1375);
DISPLAY INVISIBLE (-3800 1375);
FORCEPROP 1 LAST OFFPAGE TRUE
J 0
(-3600 1350);
DISPLAY 0.872340 (-3600 1350);
PAINT GREEN (-3600 1350);
DISPLAY INVISIBLE (-3600 1350);
FORCEPROP 2 LAST CDS_LIB standard
J 0
(-3925 1475);
DISPLAY INVISIBLE (-3925 1475);
FORCEADD Q_RES..2
(-2150 1075);
FORCEPROP 1 LAST LOCATION R821
J 0
(-2105 1200);
DISPLAY 0.489362 (-2105 1200);
PAINT SKYBLUE (-2105 1200);
FORCEPROP 2 LAST $SEC 1
J 0
(-2100 1300);
DISPLAY 0.680851 (-2100 1300);
PAINT MONO (-2100 1300);
DISPLAY INVISIBLE (-2100 1300);
FORCEPROP 2 LAST CDS_SEC 1
J 0
(-2100 1300);
DISPLAY 0.680851 (-2100 1300);
DISPLAY INVISIBLE (-2100 1300);
FORCEPROP 1 LASTPIN (-2150 1175) $PN 1
J 0
(-2145 1137);
DISPLAY 0.489362 (-2145 1137);
PAINT MONO (-2145 1137);
FORCEPROP 1 LASTPIN (-2150 975) $PN 2
J 0
(-2145 985);
DISPLAY 0.489362 (-2145 985);
PAINT MONO (-2145 985);
FORCEPROP 1 LAST PACK_TYPE 0402LF
J 0
(-2125 1025);
DISPLAY 0.489362 (-2125 1025);
PAINT SKYBLUE (-2125 1025);
FORCEPROP 1 LAST VALUE 10K
J 0
(-2125 1125);
DISPLAY 0.489362 (-2125 1125);
PAINT SKYBLUE (-2125 1125);
FORCEPROP 1 LAST TOLERANCE 5%
J 0
(-2125 1100);
DISPLAY 0.489362 (-2125 1100);
PAINT SKYBLUE (-2125 1100);
FORCEPROP 1 LAST MATERIAL CHIP
J 0
(-2125 1050);
DISPLAY 0.489362 (-2125 1050);
PAINT SKYBLUE (-2125 1050);
FORCEPROP 1 LAST WATTAGE 1/16W
J 0
(-2125 1075);
DISPLAY 0.489362 (-2125 1075);
PAINT SKYBLUE (-2125 1075);
FORCEPROP 1 LAST PART_NUMBER TMP_QCS31002JB28
J 2
(-2175 1000);
DISPLAY 0.489362 (-2175 1000);
PAINT SKYBLUE (-2175 1000);
DISPLAY INVISIBLE (-2175 1000);
FORCEPROP 1 LAST PATH I185
J 0
(-2100 1250);
DISPLAY 0.978723 (-2100 1250);
PAINT WHITE (-2100 1250);
DISPLAY INVISIBLE (-2100 1250);
FORCEPROP 2 LAST CDS_LIB pure_quanta
J 0
(-2150 1075);
DISPLAY INVISIBLE (-2150 1075);
FORCEADD Q_RES..1
R 1
(-2375 1100);
FORCEPROP 1 LAST LOCATION R820
R 1
J 0
(-2425 1050);
DISPLAY 0.489362 (-2425 1050);
PAINT SKYBLUE (-2425 1050);
FORCEPROP 2 LAST $SEC 1
J 0
(-2325 1200);
DISPLAY 0.680851 (-2325 1200);
PAINT MONO (-2325 1200);
DISPLAY INVISIBLE (-2325 1200);
FORCEPROP 2 LAST CDS_SEC 1
J 0
(-2325 1200);
DISPLAY 0.680851 (-2325 1200);
DISPLAY INVISIBLE (-2325 1200);
FORCEPROP 1 LASTPIN (-2375 1000) $PN 1
R 1
J 0
(-2387 1012);
DISPLAY 0.489362 (-2387 1012);
PAINT MONO (-2387 1012);
FORCEPROP 1 LASTPIN (-2375 1200) $PN 2
R 1
J 0
(-2387 1162);
DISPLAY 0.489362 (-2387 1162);
PAINT MONO (-2387 1162);
FORCEPROP 1 LAST PACK_TYPE 0402LF
J 0
(-2325 1025);
DISPLAY 0.489362 (-2325 1025);
PAINT SKYBLUE (-2325 1025);
FORCEPROP 1 LAST VALUE 10K
J 0
(-2325 1175);
DISPLAY 0.489362 (-2325 1175);
PAINT SKYBLUE (-2325 1175);
FORCEPROP 1 LAST TOLERANCE 5%
J 0
(-2325 1125);
DISPLAY 0.489362 (-2325 1125);
PAINT SKYBLUE (-2325 1125);
FORCEPROP 1 LAST MATERIAL EMPTY
J 0
(-2325 975);
DISPLAY 0.489362 (-2325 975);
PAINT RED (-2325 975);
FORCEPROP 1 LAST WATTAGE 1/16W
J 0
(-2325 1075);
DISPLAY 0.489362 (-2325 1075);
PAINT SKYBLUE (-2325 1075);
FORCEPROP 1 LAST PART_NUMBER TMP_QCS31002JB28
R 1
J 0
(-2475 1050);
DISPLAY 0.638298 (-2475 1050);
PAINT SKYBLUE (-2475 1050);
DISPLAY INVISIBLE (-2475 1050);
FORCEPROP 1 LAST PATH I186
R 1
J 0
(-2525 1050);
DISPLAY 0.978723 (-2525 1050);
PAINT WHITE (-2525 1050);
DISPLAY INVISIBLE (-2525 1050);
FORCEPROP 2 LAST CDS_LIB pure_quanta
J 0
(-2375 1100);
DISPLAY INVISIBLE (-2375 1100);
FORCEADD Q_CAP..1
(-2575 1150);
FORCEPROP 1 LAST LOCATION C364
J 0
(-2525 1250);
DISPLAY 0.489362 (-2525 1250);
PAINT SKYBLUE (-2525 1250);
FORCEPROP 2 LAST $SEC 1
J 0
(-2525 1350);
DISPLAY 0.680851 (-2525 1350);
PAINT MONO (-2525 1350);
DISPLAY INVISIBLE (-2525 1350);
FORCEPROP 2 LAST CDS_SEC 1
J 0
(-2525 1350);
DISPLAY 0.680851 (-2525 1350);
DISPLAY INVISIBLE (-2525 1350);
FORCEPROP 1 LASTPIN (-2575 1250) $PN 1
J 0
(-2565 1230);
DISPLAY 0.489362 (-2565 1230);
PAINT MONO (-2565 1230);
FORCEPROP 1 LASTPIN (-2575 1050) $PN 2
J 0
(-2565 1030);
DISPLAY 0.489362 (-2565 1030);
PAINT MONO (-2565 1030);
FORCEPROP 1 LAST PACK_TYPE C0402
J 0
(-2525 1050);
DISPLAY 0.489362 (-2525 1050);
PAINT SKYBLUE (-2525 1050);
FORCEPROP 1 LAST VOLTAGE 50V
J 0
(-2525 1150);
DISPLAY 0.489362 (-2525 1150);
PAINT SKYBLUE (-2525 1150);
FORCEPROP 1 LAST VALUE 220PF
J 0
(-2525 1200);
DISPLAY 0.489362 (-2525 1200);
PAINT SKYBLUE (-2525 1200);
FORCEPROP 1 LAST TOLERANCE 5%
J 0
(-2525 1100);
DISPLAY 0.489362 (-2525 1100);
PAINT SKYBLUE (-2525 1100);
FORCEPROP 1 LAST PART_NUMBER CH12206JB00
J 0
(-2525 1000);
DISPLAY 0.404255 (-2525 1000);
PAINT SKYBLUE (-2525 1000);
DISPLAY INVISIBLE (-2525 1000);
FORCEPROP 1 LAST MATERIAL C0G
J 0
(-2525 1050);
DISPLAY 0.404255 (-2525 1050);
PAINT SKYBLUE (-2525 1050);
DISPLAY INVISIBLE (-2525 1050);
FORCEPROP 1 LAST PATH I187
J 0
(-2525 1300);
DISPLAY 0.978723 (-2525 1300);
PAINT WHITE (-2525 1300);
DISPLAY INVISIBLE (-2525 1300);
FORCEPROP 2 LAST CDS_LIB pure_quanta
J 0
(-2575 1150);
DISPLAY INVISIBLE (-2575 1150);
FORCEADD UNIVERSAL_GND..1
R 2
(-2575 950);
FORCEPROP 3 LASTPIN (-2575 1000) SIG_NAME GND\g
J 0
(-2565 1010);
DISPLAY 0.659574 (-2565 1010);
PAINT MONO (-2565 1010);
DISPLAY INVISIBLE (-2565 1010);
FORCEPROP 1 LAST HDL_POWER GND
J 1
(-2600 875);
DISPLAY 0.872340 (-2600 875);
PAINT GREEN (-2600 875);
DISPLAY INVISIBLE (-2600 875);
FORCEPROP 1 LAST PATH I188
J 2
(-2650 950);
DISPLAY 0.872340 (-2650 950);
PAINT AQUA (-2650 950);
DISPLAY INVISIBLE (-2650 950);
FORCEPROP 2 LAST CDS_LIB pure_quanta_power
J 0
(-2575 950);
DISPLAY INVISIBLE (-2575 950);
FORCEADD UNIVERSAL_GND..1
R 2
(-2775 950);
FORCEPROP 3 LASTPIN (-2775 1000) SIG_NAME GND\g
J 0
(-2765 1010);
DISPLAY 0.659574 (-2765 1010);
PAINT MONO (-2765 1010);
DISPLAY INVISIBLE (-2765 1010);
FORCEPROP 1 LAST HDL_POWER GND
J 1
(-2800 875);
DISPLAY 0.872340 (-2800 875);
PAINT GREEN (-2800 875);
DISPLAY INVISIBLE (-2800 875);
FORCEPROP 1 LAST PATH I189
J 2
(-2850 950);
DISPLAY 0.872340 (-2850 950);
PAINT AQUA (-2850 950);
DISPLAY INVISIBLE (-2850 950);
FORCEPROP 2 LAST CDS_LIB pure_quanta_power
J 0
(-2775 950);
DISPLAY INVISIBLE (-2775 950);
FORCEADD Q_CAP..1
(-2775 1150);
FORCEPROP 1 LAST LOCATION C363
J 0
(-2725 1250);
DISPLAY 0.489362 (-2725 1250);
PAINT SKYBLUE (-2725 1250);
FORCEPROP 2 LAST $SEC 1
J 0
(-2725 1350);
DISPLAY 0.680851 (-2725 1350);
PAINT MONO (-2725 1350);
DISPLAY INVISIBLE (-2725 1350);
FORCEPROP 2 LAST CDS_SEC 1
J 0
(-2725 1350);
DISPLAY 0.680851 (-2725 1350);
DISPLAY INVISIBLE (-2725 1350);
FORCEPROP 1 LASTPIN (-2775 1250) $PN 1
J 0
(-2765 1230);
DISPLAY 0.489362 (-2765 1230);
PAINT MONO (-2765 1230);
FORCEPROP 1 LASTPIN (-2775 1050) $PN 2
J 0
(-2765 1030);
DISPLAY 0.489362 (-2765 1030);
PAINT MONO (-2765 1030);
FORCEPROP 1 LAST PACK_TYPE C0402
J 0
(-2725 1050);
DISPLAY 0.489362 (-2725 1050);
PAINT SKYBLUE (-2725 1050);
FORCEPROP 1 LAST VOLTAGE 50V
J 0
(-2725 1150);
DISPLAY 0.489362 (-2725 1150);
PAINT SKYBLUE (-2725 1150);
FORCEPROP 1 LAST VALUE 220PF
J 0
(-2725 1200);
DISPLAY 0.489362 (-2725 1200);
PAINT SKYBLUE (-2725 1200);
FORCEPROP 1 LAST TOLERANCE 5%
J 0
(-2725 1100);
DISPLAY 0.489362 (-2725 1100);
PAINT SKYBLUE (-2725 1100);
FORCEPROP 1 LAST PART_NUMBER CH12206JB00
J 0
(-2725 1000);
DISPLAY 0.404255 (-2725 1000);
PAINT SKYBLUE (-2725 1000);
DISPLAY INVISIBLE (-2725 1000);
FORCEPROP 1 LAST MATERIAL C0G
J 0
(-2725 1050);
DISPLAY 0.404255 (-2725 1050);
PAINT SKYBLUE (-2725 1050);
DISPLAY INVISIBLE (-2725 1050);
FORCEPROP 1 LAST PATH I190
J 0
(-2725 1300);
DISPLAY 0.978723 (-2725 1300);
PAINT WHITE (-2725 1300);
DISPLAY INVISIBLE (-2725 1300);
FORCEPROP 2 LAST CDS_LIB pure_quanta
J 0
(-2775 1150);
DISPLAY INVISIBLE (-2775 1150);
FORCEADD Q_RES..1
(-3075 3275);
FORCEPROP 1 LAST LOCATION R818
J 0
(-3250 3275);
DISPLAY 0.489362 (-3250 3275);
PAINT SKYBLUE (-3250 3275);
FORCEPROP 2 LAST $SEC 1
J 0
(-3125 3475);
DISPLAY 0.680851 (-3125 3475);
PAINT MONO (-3125 3475);
DISPLAY INVISIBLE (-3125 3475);
FORCEPROP 2 LAST CDS_SEC 1
J 0
(-3125 3475);
DISPLAY 0.680851 (-3125 3475);
DISPLAY INVISIBLE (-3125 3475);
FORCEPROP 1 LASTPIN (-3175 3275) $PN 1
J 0
(-3163 3287);
DISPLAY 0.489362 (-3163 3287);
PAINT MONO (-3163 3287);
FORCEPROP 1 LASTPIN (-2975 3275) $PN 2
J 0
(-3013 3287);
DISPLAY 0.489362 (-3013 3287);
PAINT MONO (-3013 3287);
FORCEPROP 1 LAST VALUE 0
J 2
(-2875 3275);
DISPLAY 0.489362 (-2875 3275);
PAINT SKYBLUE (-2875 3275);
FORCEPROP 1 LAST PACK_TYPE 0402LF
J 0
(-3025 3200);
DISPLAY 0.489362 (-3025 3200);
PAINT SKYBLUE (-3025 3200);
DISPLAY INVISIBLE (-3025 3200);
FORCEPROP 1 LAST PART_NUMBER CS00002JB38
J 0
(-3050 3325);
DISPLAY 0.489362 (-3050 3325);
PAINT SKYBLUE (-3050 3325);
DISPLAY INVISIBLE (-3050 3325);
FORCEPROP 1 LAST TOLERANCE 5%
J 0
(-3100 3200);
DISPLAY 0.489362 (-3100 3200);
PAINT SKYBLUE (-3100 3200);
DISPLAY INVISIBLE (-3100 3200);
FORCEPROP 1 LAST MATERIAL CHIP
J 0
(-2650 3200);
DISPLAY 0.489362 (-2650 3200);
PAINT SKYBLUE (-2650 3200);
DISPLAY INVISIBLE (-2650 3200);
FORCEPROP 1 LAST WATTAGE 1/16W
J 2
(-2675 3200);
DISPLAY 0.489362 (-2675 3200);
PAINT SKYBLUE (-2675 3200);
DISPLAY INVISIBLE (-2675 3200);
FORCEPROP 1 LAST PATH I192
J 0
(-3125 3425);
DISPLAY 0.978723 (-3125 3425);
PAINT WHITE (-3125 3425);
DISPLAY INVISIBLE (-3125 3425);
FORCEPROP 2 LAST CDS_LIB pure_quanta
J 0
(-3075 3275);
DISPLAY INVISIBLE (-3075 3275);
FORCEADD OFFPAGE..1
R 2
(-1950 3225);
FORCEPROP 2 LAST $XR0 141 
J 0
(-1764 3225);
DISPLAY 0.638298 (-1764 3225);
PAINT MONO (-1764 3225);
FORCEPROP 2 LAST PATH I193
J 0
(-1775 3300);
DISPLAY 1.021277 (-1775 3300);
DISPLAY INVISIBLE (-1775 3300);
FORCEPROP 1 LAST COMMENT_BODY TRUE
J 2
(-2080 3125);
DISPLAY 1.106383 (-2080 3125);
PAINT PEACH (-2080 3125);
DISPLAY INVISIBLE (-2080 3125);
FORCEPROP 1 LAST OFFPAGE TRUE
J 2
(-2280 3095);
PAINT GREEN (-2280 3095);
DISPLAY INVISIBLE (-2280 3095);
FORCEPROP 2 LAST CDS_LIB standard
J 0
(-1950 3225);
DISPLAY INVISIBLE (-1950 3225);
FORCEADD OFFPAGE..2
(-1950 3275);
FORCEPROP 2 LAST $XR0 141 
J 0
(-1761 3275);
DISPLAY 0.638298 (-1761 3275);
PAINT MONO (-1761 3275);
FORCEPROP 2 LAST PATH I194
J 0
(-1775 3350);
DISPLAY 1.021277 (-1775 3350);
DISPLAY INVISIBLE (-1775 3350);
FORCEPROP 1 LAST COMMENT_BODY TRUE
J 0
(-1995 3180);
DISPLAY 0.872340 (-1995 3180);
PAINT PEACH (-1995 3180);
DISPLAY INVISIBLE (-1995 3180);
FORCEPROP 1 LAST OFFPAGE TRUE
J 0
(-1625 3150);
DISPLAY 0.872340 (-1625 3150);
PAINT GREEN (-1625 3150);
DISPLAY INVISIBLE (-1625 3150);
FORCEPROP 2 LAST CDS_LIB standard
J 0
(-1950 3275);
DISPLAY INVISIBLE (-1950 3275);
FORCEADD CONN4_HFK1040L0P1L7H..1
(-1325 1450);
FORCEPROP 1 LAST LOCATION J13
J 0
(-1400 1725);
DISPLAY 0.489362 (-1400 1725);
PAINT SKYBLUE (-1400 1725);
FORCEPROP 2 LAST $SEC 1
J 0
(-1400 1875);
DISPLAY 0.680851 (-1400 1875);
PAINT MONO (-1400 1875);
DISPLAY INVISIBLE (-1400 1875);
FORCEPROP 2 LAST CDS_SEC 1
J 0
(-1400 1875);
DISPLAY 0.680851 (-1400 1875);
DISPLAY INVISIBLE (-1400 1875);
FORCEPROP 2 LASTPIN (-1550 1375) $PN 1
J 2
(-1560 1385);
DISPLAY 0.489362 (-1560 1385);
PAINT MONO (-1560 1385);
FORCEPROP 2 LASTPIN (-1550 1425) $PN 2
J 2
(-1560 1435);
DISPLAY 0.489362 (-1560 1435);
PAINT MONO (-1560 1435);
FORCEPROP 2 LASTPIN (-1550 1475) $PN 3
J 2
(-1560 1485);
DISPLAY 0.489362 (-1560 1485);
PAINT MONO (-1560 1485);
FORCEPROP 2 LASTPIN (-1550 1525) $PN 4
J 2
(-1560 1535);
DISPLAY 0.489362 (-1560 1535);
PAINT MONO (-1560 1535);
FORCEPROP 1 LAST PART_NUMBER DFHD04MS460
J 0
(-1400 1650);
DISPLAY 0.489362 (-1400 1650);
PAINT SKYBLUE (-1400 1650);
FORCEPROP 2 LAST VALUE CONN4_HFK1040-L0P1L-7H
J 0
(-1400 1775);
DISPLAY 0.489362 (-1400 1775);
PAINT SKYBLUE (-1400 1775);
FORCEPROP 1 LAST MATERIAL IO
J 0
(-1398 1591);
DISPLAY 0.489362 (-1398 1591);
PAINT SKYBLUE (-1398 1591);
FORCEPROP 2 LAST PART_TYPE THLF
J 0
(-1400 1825);
DISPLAY 1.021277 (-1400 1825);
FORCEPROP 1 LAST PATH I195
J 0
(-1325 1450);
DISPLAY 0.723404 (-1325 1450);
PAINT GREEN (-1325 1450);
DISPLAY INVISIBLE (-1325 1450);
FORCEPROP 1 LAST NEEDS_NO_SIZE TRUE
J 0
(-1325 1450);
DISPLAY 0.723404 (-1325 1450);
PAINT GREEN (-1325 1450);
DISPLAY INVISIBLE (-1325 1450);
FORCEPROP 1 LAST CDS_LMAN_SYM_OUTLINE -75,125,75,-125
J 0
(-1325 1450);
DISPLAY 0.468085 (-1325 1450);
PAINT GREEN (-1325 1450);
DISPLAY INVISIBLE (-1325 1450);
FORCEPROP 2 LAST CDS_LIB pure_quanta
J 0
(-1325 1450);
DISPLAY INVISIBLE (-1325 1450);
FORCEADD Q_RES..2
(-6925 3950);
FORCEPROP 1 LAST LOCATION R816
J 0
(-6880 4075);
DISPLAY 0.489362 (-6880 4075);
PAINT SKYBLUE (-6880 4075);
FORCEPROP 2 LAST $SEC 1
J 0
(-6875 4175);
DISPLAY 0.680851 (-6875 4175);
PAINT MONO (-6875 4175);
DISPLAY INVISIBLE (-6875 4175);
FORCEPROP 2 LAST CDS_SEC 1
J 0
(-6875 4175);
DISPLAY 0.680851 (-6875 4175);
DISPLAY INVISIBLE (-6875 4175);
FORCEPROP 1 LASTPIN (-6925 4050) $PN 1
J 0
(-6920 4012);
DISPLAY 0.489362 (-6920 4012);
PAINT MONO (-6920 4012);
FORCEPROP 1 LASTPIN (-6925 3850) $PN 2
J 0
(-6920 3860);
DISPLAY 0.489362 (-6920 3860);
PAINT MONO (-6920 3860);
FORCEPROP 1 LAST TOLERANCE 5%
J 0
(-6875 3975);
DISPLAY 0.489362 (-6875 3975);
PAINT SKYBLUE (-6875 3975);
FORCEPROP 1 LAST PACK_TYPE 0402LF
J 0
(-6875 3900);
DISPLAY 0.489362 (-6875 3900);
PAINT SKYBLUE (-6875 3900);
FORCEPROP 1 LAST WATTAGE 1/16W
J 0
(-6875 3950);
DISPLAY 0.489362 (-6875 3950);
PAINT SKYBLUE (-6875 3950);
FORCEPROP 1 LAST VALUE 10K
J 0
(-6875 4000);
DISPLAY 0.489362 (-6875 4000);
PAINT SKYBLUE (-6875 4000);
FORCEPROP 1 LAST MATERIAL CHIP
J 0
(-6875 3925);
DISPLAY 0.489362 (-6875 3925);
PAINT SKYBLUE (-6875 3925);
FORCEPROP 2 LAST CDS_LIB pure_quanta
J 2
(-6925 3950);
DISPLAY INVISIBLE (-6925 3950);
FORCEPROP 1 LAST PATH I196
J 0
(-6875 4125);
DISPLAY 0.978723 (-6875 4125);
PAINT WHITE (-6875 4125);
DISPLAY INVISIBLE (-6875 4125);
FORCEPROP 1 LAST PART_NUMBER TMP_QCS31002JB28
J 0
(-6875 3875);
DISPLAY 0.489362 (-6875 3875);
PAINT SKYBLUE (-6875 3875);
DISPLAY INVISIBLE (-6875 3875);
FORCEADD Q_RES..2
(-7125 3950);
FORCEPROP 1 LAST LOCATION R815
J 0
(-7080 4075);
DISPLAY 0.489362 (-7080 4075);
PAINT SKYBLUE (-7080 4075);
FORCEPROP 2 LAST $SEC 1
J 0
(-7075 4175);
DISPLAY 0.680851 (-7075 4175);
PAINT MONO (-7075 4175);
DISPLAY INVISIBLE (-7075 4175);
FORCEPROP 2 LAST CDS_SEC 1
J 0
(-7075 4175);
DISPLAY 0.680851 (-7075 4175);
DISPLAY INVISIBLE (-7075 4175);
FORCEPROP 1 LASTPIN (-7125 4050) $PN 1
J 0
(-7120 4012);
DISPLAY 0.489362 (-7120 4012);
PAINT MONO (-7120 4012);
FORCEPROP 1 LASTPIN (-7125 3850) $PN 2
J 0
(-7120 3860);
DISPLAY 0.489362 (-7120 3860);
PAINT MONO (-7120 3860);
FORCEPROP 1 LAST WATTAGE 1/16W
J 0
(-7075 3950);
DISPLAY 0.489362 (-7075 3950);
PAINT SKYBLUE (-7075 3950);
FORCEPROP 1 LAST TOLERANCE 5%
J 0
(-7075 3975);
DISPLAY 0.489362 (-7075 3975);
PAINT SKYBLUE (-7075 3975);
FORCEPROP 1 LAST PACK_TYPE 0402LF
J 0
(-7075 3900);
DISPLAY 0.489362 (-7075 3900);
PAINT SKYBLUE (-7075 3900);
FORCEPROP 1 LAST MATERIAL EMPTY
J 0
(-7075 3925);
DISPLAY 0.489362 (-7075 3925);
PAINT RED (-7075 3925);
FORCEPROP 1 LAST VALUE 10K
J 0
(-7075 4000);
DISPLAY 0.489362 (-7075 4000);
PAINT SKYBLUE (-7075 4000);
FORCEPROP 1 LAST PART_NUMBER TMP_QCS31002JB28
J 0
(-7075 3875);
DISPLAY 0.489362 (-7075 3875);
PAINT SKYBLUE (-7075 3875);
DISPLAY INVISIBLE (-7075 3875);
FORCEPROP 1 LAST PATH I197
J 0
(-7075 4125);
DISPLAY 0.978723 (-7075 4125);
PAINT WHITE (-7075 4125);
DISPLAY INVISIBLE (-7075 4125);
FORCEPROP 2 LAST CDS_LIB pure_quanta
J 0
(-7125 3950);
DISPLAY INVISIBLE (-7125 3950);
FORCEADD Q_RES..2
(-7350 3950);
FORCEPROP 1 LAST LOCATION R814
J 0
(-7305 4075);
DISPLAY 0.489362 (-7305 4075);
PAINT SKYBLUE (-7305 4075);
FORCEPROP 2 LAST $SEC 1
J 0
(-7300 4175);
DISPLAY 0.680851 (-7300 4175);
PAINT MONO (-7300 4175);
DISPLAY INVISIBLE (-7300 4175);
FORCEPROP 2 LAST CDS_SEC 1
J 0
(-7300 4175);
DISPLAY 0.680851 (-7300 4175);
DISPLAY INVISIBLE (-7300 4175);
FORCEPROP 1 LASTPIN (-7350 4050) $PN 1
J 0
(-7345 4012);
DISPLAY 0.489362 (-7345 4012);
PAINT MONO (-7345 4012);
FORCEPROP 1 LASTPIN (-7350 3850) $PN 2
J 0
(-7345 3860);
DISPLAY 0.489362 (-7345 3860);
PAINT MONO (-7345 3860);
FORCEPROP 1 LAST TOLERANCE 5%
J 0
(-7300 3975);
DISPLAY 0.489362 (-7300 3975);
PAINT SKYBLUE (-7300 3975);
FORCEPROP 1 LAST WATTAGE 1/16W
J 0
(-7300 3950);
DISPLAY 0.489362 (-7300 3950);
PAINT SKYBLUE (-7300 3950);
FORCEPROP 1 LAST MATERIAL EMPTY
J 0
(-7300 3925);
DISPLAY 0.489362 (-7300 3925);
PAINT RED (-7300 3925);
FORCEPROP 1 LAST PACK_TYPE 0402LF
J 0
(-7300 3900);
DISPLAY 0.489362 (-7300 3900);
PAINT SKYBLUE (-7300 3900);
FORCEPROP 1 LAST VALUE 10K
J 0
(-7300 4000);
DISPLAY 0.489362 (-7300 4000);
PAINT SKYBLUE (-7300 4000);
FORCEPROP 1 LAST PART_NUMBER TMP_QCS31002JB28
J 0
(-7300 3875);
DISPLAY 0.489362 (-7300 3875);
PAINT SKYBLUE (-7300 3875);
DISPLAY INVISIBLE (-7300 3875);
FORCEPROP 1 LAST PATH I198
J 0
(-7300 4125);
DISPLAY 0.978723 (-7300 4125);
PAINT WHITE (-7300 4125);
DISPLAY INVISIBLE (-7300 4125);
FORCEPROP 2 LAST CDS_LIB pure_quanta
J 0
(-7350 3950);
DISPLAY INVISIBLE (-7350 3950);
FORCEADD Q_RES..2
(-7550 3950);
FORCEPROP 1 LAST LOCATION R813
J 0
(-7505 4075);
DISPLAY 0.489362 (-7505 4075);
PAINT SKYBLUE (-7505 4075);
FORCEPROP 2 LAST $SEC 1
J 0
(-7500 4175);
DISPLAY 0.680851 (-7500 4175);
PAINT MONO (-7500 4175);
DISPLAY INVISIBLE (-7500 4175);
FORCEPROP 2 LAST CDS_SEC 1
J 0
(-7500 4175);
DISPLAY 0.680851 (-7500 4175);
DISPLAY INVISIBLE (-7500 4175);
FORCEPROP 1 LASTPIN (-7550 4050) $PN 1
J 0
(-7545 4012);
DISPLAY 0.489362 (-7545 4012);
PAINT MONO (-7545 4012);
FORCEPROP 1 LASTPIN (-7550 3850) $PN 2
J 0
(-7545 3860);
DISPLAY 0.489362 (-7545 3860);
PAINT MONO (-7545 3860);
FORCEPROP 1 LAST TOLERANCE 5%
J 0
(-7500 3975);
DISPLAY 0.489362 (-7500 3975);
PAINT SKYBLUE (-7500 3975);
FORCEPROP 1 LAST VALUE 10K
J 0
(-7500 4000);
DISPLAY 0.489362 (-7500 4000);
PAINT SKYBLUE (-7500 4000);
FORCEPROP 1 LAST WATTAGE 1/16W
J 0
(-7500 3950);
DISPLAY 0.489362 (-7500 3950);
PAINT SKYBLUE (-7500 3950);
FORCEPROP 1 LAST PACK_TYPE 0402LF
J 0
(-7500 3900);
DISPLAY 0.489362 (-7500 3900);
PAINT SKYBLUE (-7500 3900);
FORCEPROP 1 LAST MATERIAL CHIP
J 0
(-7500 3925);
DISPLAY 0.489362 (-7500 3925);
PAINT SKYBLUE (-7500 3925);
FORCEPROP 2 LAST CDS_LIB pure_quanta
J 0
(-7550 3950);
DISPLAY INVISIBLE (-7550 3950);
FORCEPROP 1 LAST PATH I199
J 0
(-7500 4125);
DISPLAY 0.978723 (-7500 4125);
PAINT WHITE (-7500 4125);
DISPLAY INVISIBLE (-7500 4125);
FORCEPROP 1 LAST PART_NUMBER TMP_QCS31002JB28
J 0
(-7500 3875);
DISPLAY 0.489362 (-7500 3875);
PAINT SKYBLUE (-7500 3875);
DISPLAY INVISIBLE (-7500 3875);
FORCEADD OFFPAGE..2
(-5800 3700);
FORCEPROP 2 LAST $XR2 141 
J 0
(-5611 3736);
DISPLAY 0.638298 (-5611 3736);
PAINT MONO (-5611 3736);
FORCEPROP 2 LAST $XR1 75 
J 0
(-5611 3664);
DISPLAY 0.638298 (-5611 3664);
PAINT MONO (-5611 3664);
FORCEPROP 2 LAST $XR0 27 
J 0
(-5611 3700);
DISPLAY 0.638298 (-5611 3700);
PAINT MONO (-5611 3700);
FORCEPROP 2 LAST PATH I200
J 0
(-5625 3775);
DISPLAY 1.021277 (-5625 3775);
DISPLAY INVISIBLE (-5625 3775);
FORCEPROP 1 LAST COMMENT_BODY TRUE
J 0
(-5845 3605);
DISPLAY 0.872340 (-5845 3605);
PAINT PEACH (-5845 3605);
DISPLAY INVISIBLE (-5845 3605);
FORCEPROP 1 LAST OFFPAGE TRUE
J 0
(-5475 3575);
DISPLAY 0.872340 (-5475 3575);
PAINT GREEN (-5475 3575);
DISPLAY INVISIBLE (-5475 3575);
FORCEPROP 2 LAST CDS_LIB standard
J 0
(-5800 3700);
DISPLAY INVISIBLE (-5800 3700);
FORCEADD OFFPAGE..2
(-5800 3625);
FORCEPROP 2 LAST $XR1 141 
J 0
(-5521 3625);
DISPLAY 0.638298 (-5521 3625);
PAINT MONO (-5521 3625);
FORCEPROP 2 LAST $XR0 27 
J 0
(-5611 3625);
DISPLAY 0.638298 (-5611 3625);
PAINT MONO (-5611 3625);
FORCEPROP 2 LAST PATH I201
J 0
(-5625 3700);
DISPLAY 1.021277 (-5625 3700);
DISPLAY INVISIBLE (-5625 3700);
FORCEPROP 1 LAST COMMENT_BODY TRUE
J 0
(-5845 3530);
DISPLAY 0.872340 (-5845 3530);
PAINT PEACH (-5845 3530);
DISPLAY INVISIBLE (-5845 3530);
FORCEPROP 1 LAST OFFPAGE TRUE
J 0
(-5475 3500);
DISPLAY 0.872340 (-5475 3500);
PAINT GREEN (-5475 3500);
DISPLAY INVISIBLE (-5475 3500);
FORCEPROP 2 LAST CDS_LIB standard
J 0
(-5800 3625);
DISPLAY INVISIBLE (-5800 3625);
FORCEADD OFFPAGE..2
(-5800 3575);
FORCEPROP 2 LAST $XR1 27 
J 0
(-5491 3575);
DISPLAY 0.638298 (-5491 3575);
PAINT MONO (-5491 3575);
FORCEPROP 2 LAST $XR0 141 
J 0
(-5611 3575);
DISPLAY 0.638298 (-5611 3575);
PAINT MONO (-5611 3575);
FORCEPROP 2 LAST PATH I202
J 0
(-5625 3650);
DISPLAY 1.021277 (-5625 3650);
DISPLAY INVISIBLE (-5625 3650);
FORCEPROP 1 LAST COMMENT_BODY TRUE
J 0
(-5845 3480);
DISPLAY 0.872340 (-5845 3480);
PAINT PEACH (-5845 3480);
DISPLAY INVISIBLE (-5845 3480);
FORCEPROP 1 LAST OFFPAGE TRUE
J 0
(-5475 3450);
DISPLAY 0.872340 (-5475 3450);
PAINT GREEN (-5475 3450);
DISPLAY INVISIBLE (-5475 3450);
FORCEPROP 2 LAST CDS_LIB standard
J 0
(-5800 3575);
DISPLAY INVISIBLE (-5800 3575);
FORCEADD Q_RES..2
(-725 3900);
FORCEPROP 1 LAST LOCATION R825
J 0
(-680 4025);
DISPLAY 0.489362 (-680 4025);
PAINT SKYBLUE (-680 4025);
FORCEPROP 2 LAST $SEC 1
J 0
(-675 4125);
DISPLAY 0.680851 (-675 4125);
PAINT MONO (-675 4125);
DISPLAY INVISIBLE (-675 4125);
FORCEPROP 2 LAST CDS_SEC 1
J 0
(-675 4125);
DISPLAY 0.680851 (-675 4125);
DISPLAY INVISIBLE (-675 4125);
FORCEPROP 1 LASTPIN (-725 4000) $PN 1
J 0
(-720 3962);
DISPLAY 0.489362 (-720 3962);
PAINT MONO (-720 3962);
FORCEPROP 1 LASTPIN (-725 3800) $PN 2
J 0
(-720 3810);
DISPLAY 0.489362 (-720 3810);
PAINT MONO (-720 3810);
FORCEPROP 1 LAST TOLERANCE 5%
J 0
(-675 3925);
DISPLAY 0.489362 (-675 3925);
PAINT SKYBLUE (-675 3925);
FORCEPROP 1 LAST WATTAGE 1/16W
J 0
(-675 3900);
DISPLAY 0.489362 (-675 3900);
PAINT SKYBLUE (-675 3900);
FORCEPROP 1 LAST MATERIAL EMPTY
J 0
(-675 3875);
DISPLAY 0.489362 (-675 3875);
PAINT RED (-675 3875);
FORCEPROP 1 LAST PACK_TYPE 0402LF
J 0
(-675 3850);
DISPLAY 0.489362 (-675 3850);
PAINT SKYBLUE (-675 3850);
FORCEPROP 1 LAST VALUE 10K
J 0
(-675 3950);
DISPLAY 0.489362 (-675 3950);
PAINT SKYBLUE (-675 3950);
FORCEPROP 1 LAST PART_NUMBER TMP_QCS31002JB28
J 0
(-675 3825);
DISPLAY 0.489362 (-675 3825);
PAINT SKYBLUE (-675 3825);
DISPLAY INVISIBLE (-675 3825);
FORCEPROP 1 LAST PATH I203
J 0
(-675 4075);
DISPLAY 0.978723 (-675 4075);
PAINT WHITE (-675 4075);
DISPLAY INVISIBLE (-675 4075);
FORCEPROP 2 LAST CDS_LIB pure_quanta
J 0
(-725 3900);
DISPLAY INVISIBLE (-725 3900);
FORCEADD Q_RES..2
(-925 3900);
FORCEPROP 1 LAST LOCATION R824
J 0
(-880 4025);
DISPLAY 0.489362 (-880 4025);
PAINT SKYBLUE (-880 4025);
FORCEPROP 2 LAST $SEC 1
J 0
(-875 4125);
DISPLAY 0.680851 (-875 4125);
PAINT MONO (-875 4125);
DISPLAY INVISIBLE (-875 4125);
FORCEPROP 2 LAST CDS_SEC 1
J 0
(-875 4125);
DISPLAY 0.680851 (-875 4125);
DISPLAY INVISIBLE (-875 4125);
FORCEPROP 1 LASTPIN (-925 4000) $PN 1
J 0
(-920 3962);
DISPLAY 0.489362 (-920 3962);
PAINT MONO (-920 3962);
FORCEPROP 1 LASTPIN (-925 3800) $PN 2
J 0
(-920 3810);
DISPLAY 0.489362 (-920 3810);
PAINT MONO (-920 3810);
FORCEPROP 1 LAST WATTAGE 1/16W
J 0
(-875 3900);
DISPLAY 0.489362 (-875 3900);
PAINT SKYBLUE (-875 3900);
FORCEPROP 1 LAST TOLERANCE 5%
J 0
(-875 3925);
DISPLAY 0.489362 (-875 3925);
PAINT SKYBLUE (-875 3925);
FORCEPROP 1 LAST VALUE 10K
J 0
(-875 3950);
DISPLAY 0.489362 (-875 3950);
PAINT SKYBLUE (-875 3950);
FORCEPROP 1 LAST PACK_TYPE 0402LF
J 0
(-875 3850);
DISPLAY 0.489362 (-875 3850);
PAINT SKYBLUE (-875 3850);
FORCEPROP 1 LAST MATERIAL CHIP
J 0
(-875 3875);
DISPLAY 0.489362 (-875 3875);
PAINT SKYBLUE (-875 3875);
FORCEPROP 2 LAST CDS_LIB pure_quanta
J 0
(-925 3900);
DISPLAY INVISIBLE (-925 3900);
FORCEPROP 1 LAST PATH I204
J 0
(-875 4075);
DISPLAY 0.978723 (-875 4075);
PAINT WHITE (-875 4075);
DISPLAY INVISIBLE (-875 4075);
FORCEPROP 1 LAST PART_NUMBER TMP_QCS31002JB28
J 0
(-875 3825);
DISPLAY 0.489362 (-875 3825);
PAINT SKYBLUE (-875 3825);
DISPLAY INVISIBLE (-875 3825);
FORCEADD Q_RES..2
(-1150 3900);
FORCEPROP 1 LAST LOCATION R823
J 0
(-1105 4025);
DISPLAY 0.489362 (-1105 4025);
PAINT SKYBLUE (-1105 4025);
FORCEPROP 2 LAST $SEC 1
J 0
(-1100 4125);
DISPLAY 0.680851 (-1100 4125);
PAINT MONO (-1100 4125);
DISPLAY INVISIBLE (-1100 4125);
FORCEPROP 2 LAST CDS_SEC 1
J 0
(-1100 4125);
DISPLAY 0.680851 (-1100 4125);
DISPLAY INVISIBLE (-1100 4125);
FORCEPROP 1 LASTPIN (-1150 4000) $PN 1
J 0
(-1145 3962);
DISPLAY 0.489362 (-1145 3962);
PAINT MONO (-1145 3962);
FORCEPROP 1 LASTPIN (-1150 3800) $PN 2
J 0
(-1145 3810);
DISPLAY 0.489362 (-1145 3810);
PAINT MONO (-1145 3810);
FORCEPROP 1 LAST VALUE 10K
J 0
(-1100 3950);
DISPLAY 0.489362 (-1100 3950);
PAINT SKYBLUE (-1100 3950);
FORCEPROP 1 LAST PACK_TYPE 0402LF
J 0
(-1100 3850);
DISPLAY 0.489362 (-1100 3850);
PAINT SKYBLUE (-1100 3850);
FORCEPROP 1 LAST MATERIAL EMPTY
J 0
(-1100 3875);
DISPLAY 0.489362 (-1100 3875);
PAINT RED (-1100 3875);
FORCEPROP 1 LAST TOLERANCE 5%
J 0
(-1100 3925);
DISPLAY 0.489362 (-1100 3925);
PAINT SKYBLUE (-1100 3925);
FORCEPROP 1 LAST WATTAGE 1/16W
J 0
(-1100 3900);
DISPLAY 0.489362 (-1100 3900);
PAINT SKYBLUE (-1100 3900);
FORCEPROP 1 LAST PART_NUMBER TMP_QCS31002JB28
J 0
(-1100 3825);
DISPLAY 0.489362 (-1100 3825);
PAINT SKYBLUE (-1100 3825);
DISPLAY INVISIBLE (-1100 3825);
FORCEPROP 1 LAST PATH I205
J 0
(-1100 4075);
DISPLAY 0.978723 (-1100 4075);
PAINT WHITE (-1100 4075);
DISPLAY INVISIBLE (-1100 4075);
FORCEPROP 2 LAST CDS_LIB pure_quanta
J 0
(-1150 3900);
DISPLAY INVISIBLE (-1150 3900);
FORCEADD Q_RES..2
(-1350 3900);
FORCEPROP 1 LAST LOCATION R822
J 0
(-1305 4025);
DISPLAY 0.489362 (-1305 4025);
PAINT SKYBLUE (-1305 4025);
FORCEPROP 2 LAST $SEC 1
J 0
(-1300 4125);
DISPLAY 0.680851 (-1300 4125);
PAINT MONO (-1300 4125);
DISPLAY INVISIBLE (-1300 4125);
FORCEPROP 2 LAST CDS_SEC 1
J 0
(-1300 4125);
DISPLAY 0.680851 (-1300 4125);
DISPLAY INVISIBLE (-1300 4125);
FORCEPROP 1 LASTPIN (-1350 4000) $PN 1
J 0
(-1345 3962);
DISPLAY 0.489362 (-1345 3962);
PAINT MONO (-1345 3962);
FORCEPROP 1 LASTPIN (-1350 3800) $PN 2
J 0
(-1345 3810);
DISPLAY 0.489362 (-1345 3810);
PAINT MONO (-1345 3810);
FORCEPROP 1 LAST PACK_TYPE 0402LF
J 0
(-1300 3850);
DISPLAY 0.489362 (-1300 3850);
PAINT SKYBLUE (-1300 3850);
FORCEPROP 1 LAST WATTAGE 1/16W
J 0
(-1300 3900);
DISPLAY 0.489362 (-1300 3900);
PAINT SKYBLUE (-1300 3900);
FORCEPROP 1 LAST TOLERANCE 5%
J 0
(-1300 3925);
DISPLAY 0.489362 (-1300 3925);
PAINT SKYBLUE (-1300 3925);
FORCEPROP 1 LAST VALUE 10K
J 0
(-1300 3950);
DISPLAY 0.489362 (-1300 3950);
PAINT SKYBLUE (-1300 3950);
FORCEPROP 1 LAST MATERIAL CHIP
J 0
(-1300 3875);
DISPLAY 0.489362 (-1300 3875);
PAINT SKYBLUE (-1300 3875);
FORCEPROP 2 LAST CDS_LIB pure_quanta
J 0
(-1350 3900);
DISPLAY INVISIBLE (-1350 3900);
FORCEPROP 1 LAST PATH I206
J 0
(-1300 4075);
DISPLAY 0.978723 (-1300 4075);
PAINT WHITE (-1300 4075);
DISPLAY INVISIBLE (-1300 4075);
FORCEPROP 1 LAST PART_NUMBER TMP_QCS31002JB28
J 0
(-1300 3825);
DISPLAY 0.489362 (-1300 3825);
PAINT SKYBLUE (-1300 3825);
DISPLAY INVISIBLE (-1300 3825);
FORCEADD OFFPAGE..2
R 2
(-2275 3650);
FORCEPROP 2 LAST $XR2 141 
J 0
(-2770 3650);
DISPLAY 0.638298 (-2770 3650);
PAINT MONO (-2770 3650);
FORCEPROP 2 LAST $XR1 118 
J 0
(-2650 3650);
DISPLAY 0.638298 (-2650 3650);
PAINT MONO (-2650 3650);
FORCEPROP 2 LAST $XR0 117 
J 0
(-2530 3650);
DISPLAY 0.638298 (-2530 3650);
PAINT MONO (-2530 3650);
FORCEPROP 2 LAST PATH I207
J 0
(-2225 3725);
DISPLAY 1.021277 (-2225 3725);
DISPLAY INVISIBLE (-2225 3725);
FORCEPROP 1 LAST COMMENT_BODY TRUE
J 2
(-2230 3555);
DISPLAY 0.872340 (-2230 3555);
PAINT PEACH (-2230 3555);
DISPLAY INVISIBLE (-2230 3555);
FORCEPROP 1 LAST OFFPAGE TRUE
J 2
(-2600 3525);
DISPLAY 0.872340 (-2600 3525);
PAINT GREEN (-2600 3525);
DISPLAY INVISIBLE (-2600 3525);
FORCEPROP 2 LAST CDS_LIB standard
J 0
(-2275 3650);
DISPLAY INVISIBLE (-2275 3650);
FORCEADD OFFPAGE..2
R 2
(-2275 3600);
FORCEPROP 2 LAST $XR0 141 
J 0
(-2530 3600);
DISPLAY 0.638298 (-2530 3600);
PAINT MONO (-2530 3600);
FORCEPROP 2 LAST PATH I208
J 0
(-2225 3675);
DISPLAY 1.021277 (-2225 3675);
DISPLAY INVISIBLE (-2225 3675);
FORCEPROP 1 LAST COMMENT_BODY TRUE
J 2
(-2230 3505);
DISPLAY 0.872340 (-2230 3505);
PAINT PEACH (-2230 3505);
DISPLAY INVISIBLE (-2230 3505);
FORCEPROP 1 LAST OFFPAGE TRUE
J 2
(-2600 3475);
DISPLAY 0.872340 (-2600 3475);
PAINT GREEN (-2600 3475);
DISPLAY INVISIBLE (-2600 3475);
FORCEPROP 2 LAST CDS_LIB standard
J 0
(-2275 3600);
DISPLAY INVISIBLE (-2275 3600);
FORCEADD OFFPAGE..2
R 2
(-2275 3550);
FORCEPROP 2 LAST $XR0 141 
J 0
(-2530 3550);
DISPLAY 0.638298 (-2530 3550);
PAINT MONO (-2530 3550);
FORCEPROP 2 LAST PATH I209
J 0
(-2225 3625);
DISPLAY 1.021277 (-2225 3625);
DISPLAY INVISIBLE (-2225 3625);
FORCEPROP 1 LAST COMMENT_BODY TRUE
J 2
(-2230 3455);
DISPLAY 0.872340 (-2230 3455);
PAINT PEACH (-2230 3455);
DISPLAY INVISIBLE (-2230 3455);
FORCEPROP 1 LAST OFFPAGE TRUE
J 2
(-2600 3425);
DISPLAY 0.872340 (-2600 3425);
PAINT GREEN (-2600 3425);
DISPLAY INVISIBLE (-2600 3425);
FORCEPROP 2 LAST CDS_LIB standard
J 0
(-2275 3550);
DISPLAY INVISIBLE (-2275 3550);
FORCEADD OFFPAGE..2
(-5475 2325);
FORCEPROP 2 LAST $XR0 141 
J 0
(-5286 2325);
DISPLAY 0.638298 (-5286 2325);
PAINT MONO (-5286 2325);
FORCEPROP 2 LAST PATH I210
J 0
(-5275 2375);
DISPLAY 0.680851 (-5275 2375);
DISPLAY INVISIBLE (-5275 2375);
FORCEPROP 1 LAST COMMENT_BODY TRUE
J 0
(-5520 2230);
DISPLAY 0.872340 (-5520 2230);
PAINT PEACH (-5520 2230);
DISPLAY INVISIBLE (-5520 2230);
FORCEPROP 1 LAST OFFPAGE TRUE
J 0
(-5150 2200);
DISPLAY 0.872340 (-5150 2200);
PAINT GREEN (-5150 2200);
DISPLAY INVISIBLE (-5150 2200);
FORCEPROP 2 LAST CDS_LIB standard
J 0
(-5475 2325);
DISPLAY INVISIBLE (-5475 2325);
FORCEADD Q_RES..1
R 2
(-6250 2325);
FORCEPROP 1 LAST LOCATION R1253
J 2
(-6300 2325);
DISPLAY 0.489362 (-6300 2325);
PAINT SKYBLUE (-6300 2325);
FORCEPROP 0 LAST $SEC 1
J 0
(-6300 2375);
DISPLAY 0.680851 (-6300 2375);
PAINT MONO (-6300 2375);
DISPLAY INVISIBLE (-6300 2375);
FORCEPROP 0 LAST CDS_SEC 1
J 0
(-6300 2375);
DISPLAY 0.680851 (-6300 2375);
DISPLAY INVISIBLE (-6300 2375);
FORCEPROP 1 LASTPIN (-6150 2325) $PN 1
J 2
(-6162 2337);
DISPLAY 0.489362 (-6162 2337);
PAINT MONO (-6162 2337);
FORCEPROP 1 LASTPIN (-6350 2325) $PN 2
J 2
(-6312 2337);
DISPLAY 0.489362 (-6312 2337);
PAINT MONO (-6312 2337);
FORCEPROP 1 LAST VALUE 33
J 0
(-6125 2325);
DISPLAY 0.489362 (-6125 2325);
PAINT SKYBLUE (-6125 2325);
FORCEPROP 2 LAST ROOM RST_CPU0_PLD_TO_DIMM
J 0
(-6275 2425);
DISPLAY 0.744681 (-6275 2425);
PAINT RED (-6275 2425);
DISPLAY INVISIBLE (-6275 2425);
FORCEPROP 1 LAST PACK_TYPE 0402LF
J 0
(-6425 2250);
DISPLAY 0.489362 (-6425 2250);
PAINT SKYBLUE (-6425 2250);
DISPLAY INVISIBLE (-6425 2250);
FORCEPROP 1 LAST PART_NUMBER CS03302JB29
J 0
(-6350 2375);
DISPLAY 0.489362 (-6350 2375);
PAINT SKYBLUE (-6350 2375);
DISPLAY INVISIBLE (-6350 2375);
FORCEPROP 1 LAST TOLERANCE 5%
J 2
(-6125 2300);
DISPLAY 0.489362 (-6125 2300);
PAINT SKYBLUE (-6125 2300);
DISPLAY INVISIBLE (-6125 2300);
FORCEPROP 1 LAST MATERIAL CHIP
J 0
(-6425 2300);
DISPLAY 0.489362 (-6425 2300);
PAINT SKYBLUE (-6425 2300);
DISPLAY INVISIBLE (-6425 2300);
FORCEPROP 1 LAST WATTAGE 1/16W
J 0
(-6175 2250);
DISPLAY 0.489362 (-6175 2250);
PAINT SKYBLUE (-6175 2250);
DISPLAY INVISIBLE (-6175 2250);
FORCEPROP 1 LAST PATH I211
J 2
(-6200 2475);
DISPLAY 0.978723 (-6200 2475);
PAINT WHITE (-6200 2475);
DISPLAY INVISIBLE (-6200 2475);
FORCEPROP 2 LAST BOM_COST MEM
J 0
(-6275 2475);
DISPLAY 0.744681 (-6275 2475);
PAINT WHITE (-6275 2475);
DISPLAY INVISIBLE (-6275 2475);
FORCEPROP 2 LAST CDS_LIB pure_quanta
J 0
(-6250 2325);
DISPLAY INVISIBLE (-6250 2325);
FORCEADD Q_RES..1
(-2950 1425);
FORCEPROP 1 LAST LOCATION R819
J 0
(-3125 1425);
DISPLAY 0.489362 (-3125 1425);
PAINT SKYBLUE (-3125 1425);
FORCEPROP 2 LAST $SEC 1
J 0
(-3000 1625);
DISPLAY 0.680851 (-3000 1625);
PAINT MONO (-3000 1625);
DISPLAY INVISIBLE (-3000 1625);
FORCEPROP 2 LAST CDS_SEC 1
J 0
(-3000 1625);
DISPLAY 0.680851 (-3000 1625);
DISPLAY INVISIBLE (-3000 1625);
FORCEPROP 1 LASTPIN (-3050 1425) $PN 1
J 0
(-3038 1437);
DISPLAY 0.489362 (-3038 1437);
PAINT MONO (-3038 1437);
FORCEPROP 1 LASTPIN (-2850 1425) $PN 2
J 0
(-2888 1437);
DISPLAY 0.489362 (-2888 1437);
PAINT MONO (-2888 1437);
FORCEPROP 1 LAST VALUE 0
J 2
(-2750 1425);
DISPLAY 0.489362 (-2750 1425);
PAINT SKYBLUE (-2750 1425);
FORCEPROP 1 LAST PACK_TYPE 0402LF
J 0
(-2900 1350);
DISPLAY 0.489362 (-2900 1350);
PAINT SKYBLUE (-2900 1350);
DISPLAY INVISIBLE (-2900 1350);
FORCEPROP 1 LAST PART_NUMBER CS00002JB38
J 0
(-2925 1475);
DISPLAY 0.489362 (-2925 1475);
PAINT SKYBLUE (-2925 1475);
DISPLAY INVISIBLE (-2925 1475);
FORCEPROP 1 LAST TOLERANCE 5%
J 0
(-2975 1350);
DISPLAY 0.489362 (-2975 1350);
PAINT SKYBLUE (-2975 1350);
DISPLAY INVISIBLE (-2975 1350);
FORCEPROP 1 LAST MATERIAL CHIP
J 0
(-2525 1350);
DISPLAY 0.489362 (-2525 1350);
PAINT SKYBLUE (-2525 1350);
DISPLAY INVISIBLE (-2525 1350);
FORCEPROP 1 LAST WATTAGE 1/16W
J 2
(-2550 1350);
DISPLAY 0.489362 (-2550 1350);
PAINT SKYBLUE (-2550 1350);
DISPLAY INVISIBLE (-2550 1350);
FORCEPROP 1 LAST PATH I212
J 0
(-3000 1575);
DISPLAY 0.978723 (-3000 1575);
PAINT WHITE (-3000 1575);
DISPLAY INVISIBLE (-3000 1575);
FORCEPROP 2 LAST CDS_LIB pure_quanta
J 0
(-2950 1425);
DISPLAY INVISIBLE (-2950 1425);
FORCEADD OFFPAGE..2
R 2
(-3925 1425);
FORCEPROP 2 LAST $XR0 141 
J 0
(-4210 1425);
DISPLAY 0.638298 (-4210 1425);
PAINT MONO (-4210 1425);
FORCEPROP 2 LAST PATH I213
J 0
(-3875 1500);
DISPLAY 0.680851 (-3875 1500);
DISPLAY INVISIBLE (-3875 1500);
FORCEPROP 1 LAST COMMENT_BODY TRUE
J 2
(-3880 1330);
DISPLAY 0.872340 (-3880 1330);
PAINT PEACH (-3880 1330);
DISPLAY INVISIBLE (-3880 1330);
FORCEPROP 1 LAST OFFPAGE TRUE
J 2
(-4250 1300);
DISPLAY 0.872340 (-4250 1300);
PAINT GREEN (-4250 1300);
DISPLAY INVISIBLE (-4250 1300);
FORCEPROP 2 LAST CDS_LIB standard
J 0
(-3925 1425);
DISPLAY INVISIBLE (-3925 1425);
FORCEADD OFFPAGE..1
(-7725 1975);
FORCEPROP 2 LAST $XR0 80 
J 0
(-7946 1975);
DISPLAY 0.638298 (-7946 1975);
PAINT MONO (-7946 1975);
FORCEPROP 2 LAST PATH I88
J 0
(-7975 2025);
DISPLAY 1.021277 (-7975 2025);
DISPLAY INVISIBLE (-7975 2025);
FORCEPROP 1 LAST COMMENT_BODY TRUE
J 0
(-7595 1875);
DISPLAY 1.106383 (-7595 1875);
PAINT PEACH (-7595 1875);
DISPLAY INVISIBLE (-7595 1875);
FORCEPROP 1 LAST OFFPAGE TRUE
J 0
(-7395 1845);
PAINT GREEN (-7395 1845);
DISPLAY INVISIBLE (-7395 1845);
FORCEPROP 2 LAST CDS_LIB standard
J 0
(-7725 1975);
DISPLAY INVISIBLE (-7725 1975);
FORCEADD MOSFET_N_GSD..1
(-6900 2025);
FORCEPROP 1 LAST LOCATION Q61
J 0
(-6799 2070);
DISPLAY 0.489362 (-6799 2070);
PAINT SKYBLUE (-6799 2070);
FORCEPROP 0 LAST $SEC 1
J 0
(-6800 2250);
DISPLAY 0.680851 (-6800 2250);
PAINT MONO (-6800 2250);
DISPLAY INVISIBLE (-6800 2250);
FORCEPROP 0 LAST CDS_SEC 1
J 0
(-6800 2250);
DISPLAY 1.021277 (-6800 2250);
DISPLAY INVISIBLE (-6800 2250);
FORCEPROP 0 LASTPIN (-6875 2175) $PN D
R 1
J 0
(-6885 2185);
DISPLAY 0.489362 (-6885 2185);
PAINT MONO (-6885 2185);
FORCEPROP 0 LASTPIN (-7075 1975) $PN G
J 2
(-7085 1985);
DISPLAY 0.489362 (-7085 1985);
PAINT MONO (-7085 1985);
FORCEPROP 0 LASTPIN (-6875 1875) $PN S
R 1
J 2
(-6885 1865);
DISPLAY 0.489362 (-6885 1865);
PAINT MONO (-6885 1865);
FORCEPROP 2 LAST VALUE NX138BK
J 0
(-6800 2150);
DISPLAY 0.489362 (-6800 2150);
PAINT SKYBLUE (-6800 2150);
FORCEPROP 1 LAST PART_NUMBER BAM01380023
J 0
(-6799 2005);
DISPLAY 0.489362 (-6799 2005);
PAINT SKYBLUE (-6799 2005);
FORCEPROP 2 LAST PART_TYPE SMLF
J 0
(-6800 2200);
DISPLAY 1.021277 (-6800 2200);
FORCEPROP 1 LAST MATERIAL IC
J 0
(-6799 1925);
DISPLAY 0.489362 (-6799 1925);
PAINT SKYBLUE (-6799 1925);
FORCEPROP 1 LAST PATH I89
J 0
(-6900 2025);
DISPLAY 0.723404 (-6900 2025);
PAINT GREEN (-6900 2025);
DISPLAY INVISIBLE (-6900 2025);
FORCEPROP 1 LAST NEEDS_NO_SIZE TRUE
J 0
(-6900 2025);
DISPLAY 0.468085 (-6900 2025);
PAINT GREEN (-6900 2025);
DISPLAY INVISIBLE (-6900 2025);
FORCEPROP 1 LAST CDS_LMAN_SYM_OUTLINE -100,100,100,-100
J 0
(-6900 2025);
DISPLAY 0.468085 (-6900 2025);
PAINT GREEN (-6900 2025);
DISPLAY INVISIBLE (-6900 2025);
FORCEPROP 2 LAST CDS_LIB pure_quanta
J 0
(-6900 2025);
DISPLAY INVISIBLE (-6900 2025);
FORCEADD UNIVERSAL_GND..1
R 2
(-6875 1675);
FORCEPROP 3 LASTPIN (-6875 1725) SIG_NAME GND\g
J 0
(-6865 1735);
DISPLAY 0.659574 (-6865 1735);
PAINT MONO (-6865 1735);
DISPLAY INVISIBLE (-6865 1735);
FORCEPROP 1 LAST HDL_POWER GND
J 1
(-6900 1600);
DISPLAY 0.702128 (-6900 1600);
PAINT GREEN (-6900 1600);
DISPLAY INVISIBLE (-6900 1600);
FORCEPROP 1 LAST PATH I90
J 2
(-6950 1675);
DISPLAY 0.872340 (-6950 1675);
PAINT AQUA (-6950 1675);
DISPLAY INVISIBLE (-6950 1675);
FORCEPROP 2 LAST CDS_LIB pure_quanta_power
J 0
(-6875 1675);
DISPLAY INVISIBLE (-6875 1675);
FORCEADD Q_RES..2
(-6875 2550);
FORCEPROP 1 LAST LOCATION R1419
J 0
(-6830 2675);
DISPLAY 0.489362 (-6830 2675);
PAINT SKYBLUE (-6830 2675);
FORCEPROP 0 LAST $SEC 1
J 0
(-6825 2700);
DISPLAY 0.680851 (-6825 2700);
PAINT MONO (-6825 2700);
DISPLAY INVISIBLE (-6825 2700);
FORCEPROP 0 LAST CDS_SEC 1
J 0
(-6825 2700);
DISPLAY 1.021277 (-6825 2700);
DISPLAY INVISIBLE (-6825 2700);
FORCEPROP 1 LASTPIN (-6875 2650) $PN 1
J 0
(-6870 2612);
DISPLAY 0.489362 (-6870 2612);
PAINT MONO (-6870 2612);
FORCEPROP 1 LASTPIN (-6875 2450) $PN 2
J 0
(-6870 2460);
DISPLAY 0.489362 (-6870 2460);
PAINT MONO (-6870 2460);
FORCEPROP 1 LAST TOLERANCE 5%
J 0
(-6830 2575);
DISPLAY 0.489362 (-6830 2575);
PAINT SKYBLUE (-6830 2575);
FORCEPROP 1 LAST PACK_TYPE 0402LF
J 0
(-6825 2425);
DISPLAY 0.489362 (-6825 2425);
PAINT SKYBLUE (-6825 2425);
FORCEPROP 1 LAST MATERIAL CHIP
J 0
(-6835 2475);
DISPLAY 0.489362 (-6835 2475);
PAINT SKYBLUE (-6835 2475);
FORCEPROP 1 LAST WATTAGE 1/16W
J 0
(-6835 2525);
DISPLAY 0.489362 (-6835 2525);
PAINT SKYBLUE (-6835 2525);
FORCEPROP 1 LAST VALUE 4.7K
J 0
(-6830 2625);
DISPLAY 0.489362 (-6830 2625);
PAINT SKYBLUE (-6830 2625);
FORCEPROP 1 LAST PART_NUMBER TMP_QCS24702JB38
J 0
(-6835 2425);
DISPLAY 0.489362 (-6835 2425);
PAINT SKYBLUE (-6835 2425);
DISPLAY INVISIBLE (-6835 2425);
FORCEPROP 1 LAST PATH I91
J 0
(-6825 2725);
DISPLAY 0.978723 (-6825 2725);
PAINT WHITE (-6825 2725);
DISPLAY INVISIBLE (-6825 2725);
FORCEPROP 2 LAST CDS_LIB pure_quanta
J 0
(-6875 2550);
DISPLAY INVISIBLE (-6875 2550);
FORCEADD DNS..2
(-7100 3950);
PAINT RED (-7100 3950);
FORCEPROP 1 LAST COMMENT_BODY TRUE
J 0
(-7100 3950);
PAINT RED (-7100 3950);
DISPLAY INVISIBLE (-7100 3950);
FORCEPROP 2 LAST CDS_LIB mstr_misc
J 0
(-7100 3950);
DISPLAY INVISIBLE (-7100 3950);
FORCEADD DNS..2
(-1125 3900);
PAINT RED (-1125 3900);
FORCEPROP 1 LAST COMMENT_BODY TRUE
J 0
(-1125 3900);
PAINT RED (-1125 3900);
DISPLAY INVISIBLE (-1125 3900);
FORCEPROP 2 LAST CDS_LIB mstr_misc
J 0
(-1125 3900);
DISPLAY INVISIBLE (-1125 3900);
FORCEADD DNS..2
(-2300 1075);
PAINT RED (-2300 1075);
FORCEPROP 1 LAST COMMENT_BODY TRUE
R 1
J 0
(-2225 850);
DISPLAY 0.872340 (-2225 850);
PAINT PEACH (-2225 850);
DISPLAY INVISIBLE (-2225 850);
FORCEPROP 2 LAST CDS_LIB mstr_misc
J 0
(-2300 1075);
DISPLAY INVISIBLE (-2300 1075);
FORCEADD QUANTA_TITLE_BLOCK_C..1
(0 0);
FORCEPROP 0 LAST CDS_CON_LAST_MODIFIED Fri Mar 11 14:53:14 2022
J 0
(-1885 15);
DISPLAY INVISIBLE (-1885 15);
FORCEPROP 1 LAST CUSTOM_TXT_CDS <CON_LAST_MODIFIED>
J 0
(-1885 15);
DISPLAY 0.978723 (-1885 15);
FORCEPROP 2 LAST CUSTOM_TXT_CDS <XR_PAGE_TITLE>
J 0
(-7890 5250);
DISPLAY 0.638298 (-7890 5250);
PAINT PINK (-7890 5250);
DISPLAY INVISIBLE (-7890 5250);
FORCEPROP 1 LAST CUSTOM_TXT_CDS <NAME_2>
J 0
(-3175 50);
FORCEPROP 1 LAST CUSTOM_TXT_CDS <NAME_1>
J 0
(-3175 175);
FORCEPROP 1 LAST CUSTOM_TXT_CDS <Q_NUMBER>
J 0
(-1403 103);
DISPLAY 1.212766 (-1403 103);
FORCEPROP 1 LAST CUSTOM_TXT_CDS <Q_PROJ>
J 0
(-2382 102);
DISPLAY 1.212766 (-2382 102);
FORCEPROP 1 LAST CUSTOM_TXT_CDS <Q_REV>
J 0
(-184 103);
DISPLAY 1.212766 (-184 103);
FORCEPROP 1 LAST CUSTOM_TXT_CDS <CON_PAGE_NUM> OF <CON_TOTAL_PAGES>
J 0
(-446 18);
DISPLAY 0.978723 (-446 18);
FORCEPROP 1 LAST Q_TITLE UART LEVEL SHIFT
J 0
(-9300 50);
DISPLAY 2.446809 (-9300 50);
PAINT GREEN (-9300 50);
FORCEPROP 1 LAST Q_DEPT BU9
J 1
(-3763 49);
DISPLAY 1.957447 (-3763 49);
PAINT GREEN (-3763 49);
FORCEPROP 1 LAST COMMENT_BODY TRUE
J 0
(12 -13);
DISPLAY 0.978723 (12 -13);
PAINT GREEN (12 -13);
DISPLAY INVISIBLE (12 -13);
FORCEPROP 1 LAST CDS_LMAN_SYM_OUTLINE -9475,6775,100,-125
J 0
(0 0);
DISPLAY 0.468085 (0 0);
PAINT GREEN (0 0);
DISPLAY INVISIBLE (0 0);
FORCEPROP 2 LAST CDS_LIB pure_quanta
J 0
(0 0);
DISPLAY INVISIBLE (0 0);
FORCEPROP 2 LAST PAGE_BORDER TRUE
J 0
(-7890 5250);
DISPLAY 0.638298 (-7890 5250);
PAINT PINK (-7890 5250);
DISPLAY INVISIBLE (-7890 5250);
FORCEPROP 2 LAST CDS_XR_PAGE_TITLE CR-141 : @T6G_MB_LIB.T6G(SCH_1):PAGE141
J 0
(-7890 5250);
DISPLAY 0.638298 (-7890 5250);
PAINT PINK (-7890 5250);
DISPLAY INVISIBLE (-7890 5250);
FORCEADD DNS..2
(-7325 3950);
PAINT RED (-7325 3950);
FORCEPROP 1 LAST COMMENT_BODY TRUE
J 0
(-7325 3950);
PAINT RED (-7325 3950);
DISPLAY INVISIBLE (-7325 3950);
FORCEPROP 2 LAST CDS_LIB mstr_misc
J 0
(-7325 3950);
DISPLAY INVISIBLE (-7325 3950);
FORCEADD DNS..2
(-700 3900);
PAINT RED (-700 3900);
FORCEPROP 1 LAST COMMENT_BODY TRUE
J 0
(-700 3900);
PAINT RED (-700 3900);
DISPLAY INVISIBLE (-700 3900);
FORCEPROP 2 LAST CDS_LIB mstr_misc
J 0
(-700 3900);
DISPLAY INVISIBLE (-700 3900);
WIRE 16 -1 (-3950 3125)(-3950 2975);
WIRE 16 -1 (-4150 3125)(-3950 3125);
WIRE 16 -1 (-3850 3575)(-3850 3625);
WIRE 16 -1 (-5175 3575)(-5175 3625);
WIRE 16 -1 (-6875 2650)(-6875 2700);
WIRE 16 -1 (-1975 1525)(-1550 1525);
WIRE 16 -1 (-1975 1525)(-1975 1225);
WIRE 16 -1 (-2150 1275)(-2150 1175);
WIRE 16 -1 (-2375 1200)(-2375 1275);
WIRE 16 -1 (-2575 1050)(-2575 1000);
WIRE 16 -1 (-2775 1050)(-2775 1000);
WIRE 16 -1 (-6875 1875)(-6875 1725);
WIRE 16 -1 (-1350 4100)(-1150 4100);
WIRE 16 -1 (-1350 4100)(-1350 4125);
WIRE 16 -1 (-1350 4000)(-1350 4100);
WIRE 16 -1 (-1150 4100)(-925 4100);
WIRE 16 -1 (-1150 4100)(-1150 4000);
WIRE 16 -1 (-725 4100)(-925 4100);
WIRE 16 -1 (-925 4100)(-925 4000);
WIRE 16 -1 (-725 4100)(-725 4000);
WIRE 16 -1 (-1150 3800)(-1150 3650);
WIRE 16 -1 (-1150 3650)(-2225 3650);
FORCEPROP 2 LAST SIG_NAME UART_CPU0_SCM_LVC3_UART1_R_RX
J 0
(-2160 3660);
DISPLAY 0.489362 (-2160 3660);
WIRE 16 -1 (-925 3800)(-925 3600);
WIRE 16 -1 (-2225 3600)(-925 3600);
FORCEPROP 2 LAST SIG_NAME UART_CPU0_LVC3_UART0_TX
J 0
(-2160 3610);
DISPLAY 0.489362 (-2160 3610);
WIRE 16 -1 (-725 3800)(-725 3550);
WIRE 16 -1 (-2225 3550)(-725 3550);
FORCEPROP 2 LAST SIG_NAME UART_CPU0_LVC3_UART0_RX
J 0
(-2160 3560);
DISPLAY 0.489362 (-2160 3560);
WIRE 16 -1 (-7550 3850)(-7550 3575);
WIRE 16 -1 (-5850 3575)(-7550 3575);
FORCEPROP 2 LAST SIG_NAME UART_CPU0_UART0_RX
J 0
(-6775 3585);
DISPLAY 0.489362 (-6775 3585);
WIRE 16 -1 (-7350 3850)(-7350 3625);
WIRE 16 -1 (-5850 3625)(-7350 3625);
FORCEPROP 2 LAST SIG_NAME UART_CPU0_UART0_TX
J 0
(-6775 3635);
DISPLAY 0.489362 (-6775 3635);
WIRE 16 -1 (-7125 3850)(-7125 3700);
WIRE 16 -1 (-5850 3700)(-7125 3700);
FORCEPROP 2 LAST SIG_NAME UART_CPU0_SCM_UART1_TX
J 0
(-6775 3710);
DISPLAY 0.489362 (-6775 3710);
WIRE 16 -1 (-6925 3850)(-6925 3775);
WIRE 16 -1 (-6925 3775)(-5850 3775);
FORCEPROP 2 LAST SIG_NAME UART_CPU0_SCM_UART1_RX
J 0
(-6775 3785);
DISPLAY 0.489362 (-6775 3785);
WIRE 16 -1 (-6925 4175)(-6925 4200);
WIRE 16 -1 (-7125 4175)(-6925 4175);
WIRE 16 -1 (-6925 4050)(-6925 4175);
WIRE 16 -1 (-7125 4050)(-7125 4175);
WIRE 16 -1 (-7350 4175)(-7125 4175);
WIRE 16 -1 (-7350 4050)(-7350 4175);
WIRE 16 -1 (-7550 4175)(-7350 4175);
WIRE 16 -1 (-7550 4050)(-7550 4175);
WIRE 16 -1 (-4150 3475)(-3975 3475);
WIRE 16 -1 (-3975 3475)(-3975 3875);
WIRE 16 -1 (-3850 3875)(-3975 3875);
WIRE 16 -1 (-3975 3875)(-3975 3925);
WIRE 16 -1 (-3850 3825)(-3850 3875);
WIRE 16 -1 (-5175 3825)(-5175 3875);
WIRE 16 -1 (-5175 3875)(-5050 3875);
WIRE 16 -1 (-5050 3875)(-5050 3900);
WIRE 16 -1 (-5050 3475)(-5050 3875);
WIRE 16 -1 (-5050 3475)(-4900 3475);
WIRE 16 -1 (-5525 2325)(-6150 2325);
FORCEPROP 2 LAST SIG_NAME UART_LS_EN_N
J 0
(-5935 2335);
DISPLAY 0.489362 (-5935 2335);
WIRE 16 -1 (-5825 3125)(-4900 3125);
FORCEPROP 2 LAST SIG_NAME UART_LS_EN_N
J 0
(-5685 3135);
DISPLAY 0.489362 (-5685 3135);
WIRE 16 -1 (-7675 1975)(-7075 1975);
FORCEPROP 2 LAST SIG_NAME UART_LS_EN
J 0
(-7610 1985);
DISPLAY 0.489362 (-7610 1985);
WIRE 16 -1 (-6875 2175)(-6875 2325);
WIRE 16 -1 (-6350 2325)(-6875 2325);
FORCEPROP 2 LAST SIG_NAME UART_LS_EN_R_N
J 0
(-6785 2335);
DISPLAY 0.489362 (-6785 2335);
FORCEPROP 2 LASTPROP $XRERR UNIQUE?
J 0
(-7025 2335);
DISPLAY 0.638298 (-7025 2335);
PAINT MONO (-7025 2335);
DISPLAY INVISIBLE (-7025 2335);
WIRE 16 -1 (-6875 2325)(-6875 2450);
WIRE 16 -1 (-1350 3700)(-1350 3800);
WIRE 16 -1 (-1350 3700)(-2225 3700);
FORCEPROP 2 LAST SIG_NAME UART_CPU0_SCM_LVC3_UART1_TX
J 0
(-2160 3710);
DISPLAY 0.489362 (-2160 3710);
WIRE 16 -1 (-3875 1475)(-2775 1475);
WIRE 16 -1 (-1550 1475)(-2775 1475);
FORCEPROP 2 LAST SIG_NAME UART_CPU0_LVC3_UART0_TX
J 0
(-2710 1485);
DISPLAY 0.489362 (-2710 1485);
WIRE 16 -1 (-2775 1475)(-2775 1250);
WIRE 16 -1 (-1550 1425)(-2575 1425);
WIRE 16 -1 (-2575 1425)(-2575 1250);
WIRE 16 -1 (-2850 1425)(-2575 1425);
FORCEPROP 2 LAST SIG_NAME UART_CPU0_LVC3_UART0_RX
J 0
(-2710 1435);
DISPLAY 0.489362 (-2710 1435);
FORCEPROP 2 LASTPROP $XR0 141 
J 0
(-2980 1435);
DISPLAY 0.638298 (-2980 1435);
PAINT MONO (-2980 1435);
WIRE 16 -1 (-2375 1000)(-2375 950);
WIRE 16 -1 (-2375 950)(-2150 950);
WIRE 16 -1 (-1700 950)(-2150 950);
FORCEPROP 2 LAST SIG_NAME UART_VCC_J13
J 0
(-2085 960);
DISPLAY 0.489362 (-2085 960);
FORCEPROP 2 LASTPROP $XRERR UNIQUE?
J 0
(-2325 960);
DISPLAY 0.638298 (-2325 960);
PAINT MONO (-2325 960);
DISPLAY INVISIBLE (-2325 960);
WIRE 16 -1 (-2150 975)(-2150 950);
WIRE 16 -1 (-1700 1375)(-1700 950);
WIRE 16 -1 (-1700 1375)(-1550 1375);
WIRE 16 -1 (-3875 1425)(-3050 1425);
FORCEPROP 2 LAST SIG_NAME UART_CPU0_LVC3_UART0_R_RX
J 0
(-3735 1435);
DISPLAY 0.489362 (-3735 1435);
WIRE 16 -1 (-4150 3275)(-3175 3275);
FORCEPROP 2 LAST SIG_NAME UART_CPU0_LVC3_UART0_R_TX
J 0
(-4010 3285);
DISPLAY 0.489362 (-4010 3285);
FORCEPROP 2 LASTPROP $XRERR UNIQUE?
J 0
(-4250 3285);
DISPLAY 0.638298 (-4250 3285);
PAINT MONO (-4250 3285);
DISPLAY INVISIBLE (-4250 3285);
WIRE 16 -1 (-4150 3375)(-3175 3375);
FORCEPROP 2 LAST SIG_NAME UART_CPU0_SCM_LVC3_UART1_R_TX
J 0
(-4010 3385);
DISPLAY 0.489362 (-4010 3385);
FORCEPROP 2 LASTPROP $XRERR UNIQUE?
J 0
(-4250 3385);
DISPLAY 0.638298 (-4250 3385);
PAINT MONO (-4250 3385);
DISPLAY INVISIBLE (-4250 3385);
WIRE 16 -1 (-5700 3325)(-4900 3325);
FORCEPROP 2 LAST SIG_NAME UART_CPU0_SCM_UART1_R_RX
J 0
(-5560 3335);
DISPLAY 0.489362 (-5560 3335);
FORCEPROP 2 LASTPROP $XRERR UNIQUE?
J 0
(-5800 3335);
DISPLAY 0.638298 (-5800 3335);
PAINT MONO (-5800 3335);
DISPLAY INVISIBLE (-5800 3335);
WIRE 16 -1 (-5700 3225)(-4900 3225);
FORCEPROP 2 LAST SIG_NAME UART_CPU0_UART0_R_RX
J 0
(-5535 3235);
DISPLAY 0.489362 (-5535 3235);
FORCEPROP 2 LASTPROP $XRERR UNIQUE?
J 0
(-5775 3235);
DISPLAY 0.638298 (-5775 3235);
PAINT MONO (-5775 3235);
DISPLAY INVISIBLE (-5775 3235);
WIRE 16 -1 (-5900 3225)(-6625 3225);
FORCEPROP 2 LAST SIG_NAME UART_CPU0_UART0_RX
J 0
(-6600 3235);
DISPLAY 0.489362 (-6600 3235);
WIRE 16 -1 (-6625 3275)(-4900 3275);
FORCEPROP 2 LAST SIG_NAME UART_CPU0_UART0_TX
J 0
(-6600 3285);
DISPLAY 0.489362 (-6600 3285);
WIRE 16 -1 (-6625 3375)(-4900 3375);
FORCEPROP 2 LAST SIG_NAME UART_CPU0_SCM_UART1_TX
J 0
(-6600 3385);
DISPLAY 0.489362 (-6600 3385);
WIRE 16 -1 (-6625 3325)(-5900 3325);
FORCEPROP 2 LAST SIG_NAME UART_CPU0_SCM_UART1_RX
J 0
(-6600 3335);
DISPLAY 0.489362 (-6600 3335);
WIRE 16 -1 (-4150 3225)(-2000 3225);
FORCEPROP 2 LAST SIG_NAME UART_CPU0_LVC3_UART0_R_RX
J 0
(-4010 3235);
DISPLAY 0.489362 (-4010 3235);
WIRE 16 -1 (-2975 3275)(-2000 3275);
FORCEPROP 2 LAST SIG_NAME UART_CPU0_LVC3_UART0_TX
J 0
(-2750 3285);
DISPLAY 0.489362 (-2750 3285);
WIRE 16 -1 (-4150 3325)(-2025 3325);
FORCEPROP 2 LAST SIG_NAME UART_CPU0_SCM_LVC3_UART1_R_RX
J 0
(-4010 3335);
DISPLAY 0.489362 (-4010 3335);
WIRE 16 -1 (-2975 3375)(-2025 3375);
FORCEPROP 2 LAST SIG_NAME UART_CPU0_SCM_LVC3_UART1_TX
J 0
(-2750 3385);
DISPLAY 0.489362 (-2750 3385);
DOT 1 (-2775 1475);
DOT 1 (-2575 1425);
DOT 1 (-5050 3875);
DOT 1 (-3975 3875);
DOT 1 (-2150 950);
DOT 1 (-6925 4175);
DOT 1 (-7125 4175);
DOT 1 (-7350 4175);
DOT 1 (-1350 4100);
DOT 1 (-1150 4100);
DOT 1 (-6875 2325);
DOT 1 (-925 4100);
FORCENOTE
CPU0 UART1
(-9100 3300) 0;
DISPLAY LEFT (-9100 3300);
DISPLAY 3.936170 (-9100 3300);
PAINT WHITE (-9100 3300);
FORCENOTE
TO SCM UART1
(-2675 4550) 0;
DISPLAY LEFT (-2675 4550);
DISPLAY 3.936170 (-2675 4550);
PAINT WHITE (-2675 4550);
QUIT
